(kicad_sch
	(version 20250114)
	(generator "eeschema")
	(generator_version "9.0")
	(paper "A3")
	(title_block
		(title "Kintex 410T devboard")
		(date "2024-04-03")
		(rev "1.1.2")
	)
	(junction
		(at 303.53 67.31)
		(diameter 0)
		(color 0 0 0 0)
	)
	(junction
		(at 146.05 57.15)
		(diameter 0)
		(color 0 0 0 0)
	)
	(junction
		(at 288.29 57.15)
		(diameter 0)
		(color 0 0 0 0)
	)
	(junction
		(at 265.43 67.31)
		(diameter 0)
		(color 0 0 0 0)
	)
	(junction
		(at 153.67 57.15)
		(diameter 0)
		(color 0 0 0 0)
	)
	(junction
		(at 273.05 67.31)
		(diameter 0)
		(color 0 0 0 0)
	)
	(junction
		(at 130.81 67.31)
		(diameter 0)
		(color 0 0 0 0)
	)
	(junction
		(at 153.67 67.31)
		(diameter 0)
		(color 0 0 0 0)
	)
	(junction
		(at 288.29 67.31)
		(diameter 0)
		(color 0 0 0 0)
	)
	(junction
		(at 303.53 57.15)
		(diameter 0)
		(color 0 0 0 0)
	)
	(junction
		(at 265.43 57.15)
		(diameter 0)
		(color 0 0 0 0)
	)
	(junction
		(at 295.91 57.15)
		(diameter 0)
		(color 0 0 0 0)
	)
	(junction
		(at 146.05 67.31)
		(diameter 0)
		(color 0 0 0 0)
	)
	(junction
		(at 123.19 67.31)
		(diameter 0)
		(color 0 0 0 0)
	)
	(junction
		(at 138.43 67.31)
		(diameter 0)
		(color 0 0 0 0)
	)
	(junction
		(at 168.91 57.15)
		(diameter 0)
		(color 0 0 0 0)
	)
	(junction
		(at 273.05 57.15)
		(diameter 0)
		(color 0 0 0 0)
	)
	(junction
		(at 161.29 67.31)
		(diameter 0)
		(color 0 0 0 0)
	)
	(junction
		(at 257.81 57.15)
		(diameter 0)
		(color 0 0 0 0)
	)
	(junction
		(at 280.67 57.15)
		(diameter 0)
		(color 0 0 0 0)
	)
	(junction
		(at 280.67 67.31)
		(diameter 0)
		(color 0 0 0 0)
	)
	(junction
		(at 130.81 57.15)
		(diameter 0)
		(color 0 0 0 0)
	)
	(junction
		(at 161.29 57.15)
		(diameter 0)
		(color 0 0 0 0)
	)
	(junction
		(at 138.43 57.15)
		(diameter 0)
		(color 0 0 0 0)
	)
	(junction
		(at 295.91 67.31)
		(diameter 0)
		(color 0 0 0 0)
	)
	(junction
		(at 123.19 57.15)
		(diameter 0)
		(color 0 0 0 0)
	)
	(no_connect
		(at 179.07 217.17)
	)
	(no_connect
		(at 179.07 204.47)
	)
	(no_connect
		(at 248.92 196.85)
	)
	(no_connect
		(at 248.92 105.41)
	)
	(no_connect
		(at 248.92 207.01)
	)
	(no_connect
		(at 248.92 189.23)
	)
	(no_connect
		(at 248.92 199.39)
	)
	(no_connect
		(at 248.92 191.77)
	)
	(no_connect
		(at 248.92 217.17)
	)
	(no_connect
		(at 248.92 107.95)
	)
	(no_connect
		(at 248.92 97.79)
	)
	(no_connect
		(at 248.92 102.87)
	)
	(no_connect
		(at 248.92 212.09)
	)
	(no_connect
		(at 248.92 158.75)
	)
	(no_connect
		(at 248.92 181.61)
	)
	(no_connect
		(at 248.92 194.31)
	)
	(no_connect
		(at 248.92 153.67)
	)
	(no_connect
		(at 248.92 209.55)
	)
	(no_connect
		(at 248.92 115.57)
	)
	(no_connect
		(at 179.07 207.01)
	)
	(no_connect
		(at 179.07 168.91)
	)
	(no_connect
		(at 248.92 100.33)
	)
	(no_connect
		(at 248.92 95.25)
	)
	(bus_entry
		(at 153.67 143.51)
		(size -1.27 1.27)
		(stroke
			(width 0)
			(type default)
		)
	)
	(bus_entry
		(at 153.67 163.83)
		(size -1.27 1.27)
		(stroke
			(width 0)
			(type default)
		)
	)
	(bus_entry
		(at 266.7 127)
		(size -1.27 1.27)
		(stroke
			(width 0)
			(type default)
		)
	)
	(bus_entry
		(at 266.7 170.18)
		(size -1.27 1.27)
		(stroke
			(width 0)
			(type default)
		)
	)
	(bus_entry
		(at 153.67 196.85)
		(size -1.27 1.27)
		(stroke
			(width 0)
			(type default)
		)
	)
	(bus_entry
		(at 99.06 170.18)
		(size 1.27 1.27)
		(stroke
			(width 0)
			(type default)
		)
	)
	(bus_entry
		(at 153.67 156.21)
		(size -1.27 1.27)
		(stroke
			(width 0)
			(type default)
		)
	)
	(bus_entry
		(at 153.67 184.15)
		(size -1.27 1.27)
		(stroke
			(width 0)
			(type default)
		)
	)
	(bus_entry
		(at 153.67 176.53)
		(size -1.27 1.27)
		(stroke
			(width 0)
			(type default)
		)
	)
	(bus_entry
		(at 153.67 138.43)
		(size -1.27 1.27)
		(stroke
			(width 0)
			(type default)
		)
	)
	(bus_entry
		(at 99.06 114.3)
		(size 1.27 1.27)
		(stroke
			(width 0)
			(type default)
		)
	)
	(bus_entry
		(at 153.67 158.75)
		(size -1.27 1.27)
		(stroke
			(width 0)
			(type default)
		)
	)
	(bus_entry
		(at 153.67 201.93)
		(size -1.27 1.27)
		(stroke
			(width 0)
			(type default)
		)
	)
	(bus_entry
		(at 99.06 165.1)
		(size 1.27 1.27)
		(stroke
			(width 0)
			(type default)
		)
	)
	(bus_entry
		(at 128.27 96.52)
		(size 1.27 1.27)
		(stroke
			(width 0)
			(type default)
		)
	)
	(bus_entry
		(at 128.27 119.38)
		(size 1.27 1.27)
		(stroke
			(width 0)
			(type default)
		)
	)
	(bus_entry
		(at 153.67 212.09)
		(size -1.27 1.27)
		(stroke
			(width 0)
			(type default)
		)
	)
	(bus_entry
		(at 266.7 147.32)
		(size -1.27 1.27)
		(stroke
			(width 0)
			(type default)
		)
	)
	(bus_entry
		(at 266.7 172.72)
		(size -1.27 1.27)
		(stroke
			(width 0)
			(type default)
		)
	)
	(bus_entry
		(at 266.7 162.56)
		(size -1.27 1.27)
		(stroke
			(width 0)
			(type default)
		)
	)
	(bus_entry
		(at 266.7 137.16)
		(size -1.27 1.27)
		(stroke
			(width 0)
			(type default)
		)
	)
	(bus_entry
		(at 266.7 200.66)
		(size -1.27 1.27)
		(stroke
			(width 0)
			(type default)
		)
	)
	(bus_entry
		(at 266.7 121.92)
		(size -1.27 1.27)
		(stroke
			(width 0)
			(type default)
		)
	)
	(bus_entry
		(at 128.27 91.44)
		(size 1.27 1.27)
		(stroke
			(width 0)
			(type default)
		)
	)
	(bus_entry
		(at 99.06 111.76)
		(size 1.27 1.27)
		(stroke
			(width 0)
			(type default)
		)
	)
	(bus_entry
		(at 266.7 109.22)
		(size -1.27 1.27)
		(stroke
			(width 0)
			(type default)
		)
	)
	(bus_entry
		(at 128.27 93.98)
		(size 1.27 1.27)
		(stroke
			(width 0)
			(type default)
		)
	)
	(bus_entry
		(at 153.67 130.81)
		(size -1.27 1.27)
		(stroke
			(width 0)
			(type default)
		)
	)
	(bus_entry
		(at 153.67 133.35)
		(size -1.27 1.27)
		(stroke
			(width 0)
			(type default)
		)
	)
	(bus_entry
		(at 266.7 165.1)
		(size -1.27 1.27)
		(stroke
			(width 0)
			(type default)
		)
	)
	(bus_entry
		(at 153.67 135.89)
		(size -1.27 1.27)
		(stroke
			(width 0)
			(type default)
		)
	)
	(bus_entry
		(at 153.67 146.05)
		(size -1.27 1.27)
		(stroke
			(width 0)
			(type default)
		)
	)
	(bus_entry
		(at 266.7 177.8)
		(size -1.27 1.27)
		(stroke
			(width 0)
			(type default)
		)
	)
	(bus_entry
		(at 153.67 194.31)
		(size -1.27 1.27)
		(stroke
			(width 0)
			(type default)
		)
	)
	(bus_entry
		(at 266.7 91.44)
		(size -1.27 1.27)
		(stroke
			(width 0)
			(type default)
		)
	)
	(bus_entry
		(at 266.7 111.76)
		(size -1.27 1.27)
		(stroke
			(width 0)
			(type default)
		)
	)
	(bus_entry
		(at 151.13 101.6)
		(size 1.27 1.27)
		(stroke
			(width 0)
			(type default)
		)
	)
	(bus_entry
		(at 151.13 111.76)
		(size 1.27 1.27)
		(stroke
			(width 0)
			(type default)
		)
	)
	(bus_entry
		(at 153.67 214.63)
		(size -1.27 1.27)
		(stroke
			(width 0)
			(type default)
		)
	)
	(bus_entry
		(at 266.7 182.88)
		(size -1.27 1.27)
		(stroke
			(width 0)
			(type default)
		)
	)
	(bus_entry
		(at 266.7 116.84)
		(size -1.27 1.27)
		(stroke
			(width 0)
			(type default)
		)
	)
	(bus_entry
		(at 153.67 140.97)
		(size -1.27 1.27)
		(stroke
			(width 0)
			(type default)
		)
	)
	(bus_entry
		(at 153.67 128.27)
		(size -1.27 1.27)
		(stroke
			(width 0)
			(type default)
		)
	)
	(bus_entry
		(at 266.7 149.86)
		(size -1.27 1.27)
		(stroke
			(width 0)
			(type default)
		)
	)
	(bus_entry
		(at 266.7 203.2)
		(size -1.27 1.27)
		(stroke
			(width 0)
			(type default)
		)
	)
	(bus_entry
		(at 153.67 191.77)
		(size -1.27 1.27)
		(stroke
			(width 0)
			(type default)
		)
	)
	(bus_entry
		(at 153.67 123.19)
		(size -1.27 1.27)
		(stroke
			(width 0)
			(type default)
		)
	)
	(bus_entry
		(at 151.13 114.3)
		(size 1.27 1.27)
		(stroke
			(width 0)
			(type default)
		)
	)
	(bus_entry
		(at 266.7 167.64)
		(size -1.27 1.27)
		(stroke
			(width 0)
			(type default)
		)
	)
	(bus_entry
		(at 266.7 139.7)
		(size -1.27 1.27)
		(stroke
			(width 0)
			(type default)
		)
	)
	(bus_entry
		(at 153.67 153.67)
		(size -1.27 1.27)
		(stroke
			(width 0)
			(type default)
		)
	)
	(bus_entry
		(at 266.7 144.78)
		(size -1.27 1.27)
		(stroke
			(width 0)
			(type default)
		)
	)
	(bus_entry
		(at 266.7 213.36)
		(size -1.27 1.27)
		(stroke
			(width 0)
			(type default)
		)
	)
	(bus_entry
		(at 153.67 161.29)
		(size -1.27 1.27)
		(stroke
			(width 0)
			(type default)
		)
	)
	(bus_entry
		(at 128.27 96.52)
		(size 1.27 1.27)
		(stroke
			(width 0)
			(type default)
		)
	)
	(bus_entry
		(at 266.7 129.54)
		(size -1.27 1.27)
		(stroke
			(width 0)
			(type default)
		)
	)
	(bus_entry
		(at 99.06 96.52)
		(size 1.27 1.27)
		(stroke
			(width 0)
			(type default)
		)
	)
	(bus_entry
		(at 153.67 209.55)
		(size -1.27 1.27)
		(stroke
			(width 0)
			(type default)
		)
	)
	(bus_entry
		(at 151.13 116.84)
		(size 1.27 1.27)
		(stroke
			(width 0)
			(type default)
		)
	)
	(bus_entry
		(at 266.7 160.02)
		(size -1.27 1.27)
		(stroke
			(width 0)
			(type default)
		)
	)
	(bus_entry
		(at 266.7 124.46)
		(size -1.27 1.27)
		(stroke
			(width 0)
			(type default)
		)
	)
	(bus_entry
		(at 153.67 189.23)
		(size -1.27 1.27)
		(stroke
			(width 0)
			(type default)
		)
	)
	(bus_entry
		(at 266.7 154.94)
		(size -1.27 1.27)
		(stroke
			(width 0)
			(type default)
		)
	)
	(bus_entry
		(at 153.67 186.69)
		(size -1.27 1.27)
		(stroke
			(width 0)
			(type default)
		)
	)
	(bus_entry
		(at 266.7 175.26)
		(size -1.27 1.27)
		(stroke
			(width 0)
			(type default)
		)
	)
	(bus_entry
		(at 128.27 106.68)
		(size 1.27 1.27)
		(stroke
			(width 0)
			(type default)
		)
	)
	(bus_entry
		(at 153.67 179.07)
		(size -1.27 1.27)
		(stroke
			(width 0)
			(type default)
		)
	)
	(bus_entry
		(at 99.06 101.6)
		(size 1.27 1.27)
		(stroke
			(width 0)
			(type default)
		)
	)
	(bus_entry
		(at 266.7 132.08)
		(size -1.27 1.27)
		(stroke
			(width 0)
			(type default)
		)
	)
	(bus_entry
		(at 266.7 142.24)
		(size -1.27 1.27)
		(stroke
			(width 0)
			(type default)
		)
	)
	(bus_entry
		(at 99.06 116.84)
		(size 1.27 1.27)
		(stroke
			(width 0)
			(type default)
		)
	)
	(bus_entry
		(at 153.67 181.61)
		(size -1.27 1.27)
		(stroke
			(width 0)
			(type default)
		)
	)
	(bus_entry
		(at 153.67 125.73)
		(size -1.27 1.27)
		(stroke
			(width 0)
			(type default)
		)
	)
	(bus_entry
		(at 153.67 173.99)
		(size -1.27 1.27)
		(stroke
			(width 0)
			(type default)
		)
	)
	(bus_entry
		(at 266.7 185.42)
		(size -1.27 1.27)
		(stroke
			(width 0)
			(type default)
		)
	)
	(bus_entry
		(at 99.06 99.06)
		(size 1.27 1.27)
		(stroke
			(width 0)
			(type default)
		)
	)
	(bus_entry
		(at 266.7 119.38)
		(size -1.27 1.27)
		(stroke
			(width 0)
			(type default)
		)
	)
	(bus_entry
		(at 266.7 111.76)
		(size -1.27 1.27)
		(stroke
			(width 0)
			(type default)
		)
	)
	(bus_entry
		(at 99.06 109.22)
		(size 1.27 1.27)
		(stroke
			(width 0)
			(type default)
		)
	)
	(bus_entry
		(at 153.67 151.13)
		(size -1.27 1.27)
		(stroke
			(width 0)
			(type default)
		)
	)
	(bus_entry
		(at 266.7 134.62)
		(size -1.27 1.27)
		(stroke
			(width 0)
			(type default)
		)
	)
	(bus_entry
		(at 99.06 119.38)
		(size 1.27 1.27)
		(stroke
			(width 0)
			(type default)
		)
	)
	(bus_entry
		(at 99.06 93.98)
		(size 1.27 1.27)
		(stroke
			(width 0)
			(type default)
		)
	)
	(bus_entry
		(at 153.67 148.59)
		(size -1.27 1.27)
		(stroke
			(width 0)
			(type default)
		)
	)
	(bus_entry
		(at 153.67 199.39)
		(size -1.27 1.27)
		(stroke
			(width 0)
			(type default)
		)
	)
	(bus
		(pts
			(xy 266.7 165.1) (xy 266.7 167.64)
		)
		(stroke
			(width 0)
			(type default)
		)
	)
	(wire
		(pts
			(xy 177.8 88.9) (xy 177.8 57.15)
		)
		(stroke
			(width 0)
			(type default)
		)
	)
	(bus
		(pts
			(xy 99.06 93.98) (xy 99.06 96.52)
		)
		(stroke
			(width 0)
			(type default)
		)
	)
	(wire
		(pts
			(xy 257.81 67.31) (xy 257.81 64.77)
		)
		(stroke
			(width 0)
			(type default)
		)
	)
	(wire
		(pts
			(xy 179.07 161.29) (xy 153.67 161.29)
		)
		(stroke
			(width 0)
			(type default)
		)
	)
	(wire
		(pts
			(xy 123.19 67.31) (xy 130.81 67.31)
		)
		(stroke
			(width 0)
			(type default)
		)
	)
	(wire
		(pts
			(xy 303.53 57.15) (xy 295.91 57.15)
		)
		(stroke
			(width 0)
			(type default)
		)
	)
	(wire
		(pts
			(xy 152.4 113.03) (xy 149.86 113.03)
		)
		(stroke
			(width 0)
			(type default)
		)
	)
	(wire
		(pts
			(xy 179.07 130.81) (xy 153.67 130.81)
		)
		(stroke
			(width 0)
			(type default)
		)
	)
	(bus
		(pts
			(xy 152.4 149.86) (xy 152.4 152.4)
		)
		(stroke
			(width 0)
			(type default)
		)
	)
	(wire
		(pts
			(xy 265.43 156.21) (xy 248.92 156.21)
		)
		(stroke
			(width 0)
			(type default)
		)
	)
	(wire
		(pts
			(xy 179.07 176.53) (xy 153.67 176.53)
		)
		(stroke
			(width 0)
			(type default)
		)
	)
	(bus
		(pts
			(xy 151.13 81.28) (xy 151.13 101.6)
		)
		(stroke
			(width 0)
			(type default)
		)
	)
	(wire
		(pts
			(xy 265.43 57.15) (xy 257.81 57.15)
		)
		(stroke
			(width 0)
			(type default)
		)
	)
	(bus
		(pts
			(xy 99.06 99.06) (xy 99.06 101.6)
		)
		(stroke
			(width 0)
			(type default)
		)
	)
	(bus
		(pts
			(xy 152.4 210.82) (xy 152.4 213.36)
		)
		(stroke
			(width 0)
			(type default)
		)
	)
	(wire
		(pts
			(xy 265.43 92.71) (xy 248.92 92.71)
		)
		(stroke
			(width 0)
			(type default)
		)
	)
	(wire
		(pts
			(xy 129.54 95.25) (xy 179.07 95.25)
		)
		(stroke
			(width 0)
			(type default)
		)
	)
	(wire
		(pts
			(xy 179.07 191.77) (xy 153.67 191.77)
		)
		(stroke
			(width 0)
			(type default)
		)
	)
	(wire
		(pts
			(xy 146.05 67.31) (xy 138.43 67.31)
		)
		(stroke
			(width 0)
			(type default)
		)
	)
	(wire
		(pts
			(xy 146.05 57.15) (xy 153.67 57.15)
		)
		(stroke
			(width 0)
			(type default)
		)
	)
	(wire
		(pts
			(xy 168.91 67.31) (xy 161.29 67.31)
		)
		(stroke
			(width 0)
			(type default)
		)
	)
	(wire
		(pts
			(xy 303.53 57.15) (xy 303.53 59.69)
		)
		(stroke
			(width 0)
			(type default)
		)
	)
	(bus
		(pts
			(xy 266.7 134.62) (xy 266.7 137.16)
		)
		(stroke
			(width 0)
			(type default)
		)
	)
	(wire
		(pts
			(xy 146.05 113.03) (xy 100.33 113.03)
		)
		(stroke
			(width 0)
			(type default)
		)
	)
	(bus
		(pts
			(xy 267.97 87.63) (xy 266.7 88.9)
		)
		(stroke
			(width 0)
			(type default)
		)
	)
	(bus
		(pts
			(xy 151.13 226.06) (xy 95.25 226.06)
		)
		(stroke
			(width 0)
			(type default)
		)
	)
	(wire
		(pts
			(xy 250.19 57.15) (xy 250.19 88.9)
		)
		(stroke
			(width 0)
			(type default)
		)
	)
	(bus
		(pts
			(xy 99.06 88.9) (xy 99.06 93.98)
		)
		(stroke
			(width 0)
			(type default)
		)
	)
	(bus
		(pts
			(xy 152.4 198.12) (xy 152.4 200.66)
		)
		(stroke
			(width 0)
			(type default)
		)
	)
	(wire
		(pts
			(xy 265.43 171.45) (xy 248.92 171.45)
		)
		(stroke
			(width 0)
			(type default)
		)
	)
	(wire
		(pts
			(xy 110.49 210.82) (xy 110.49 212.09)
		)
		(stroke
			(width 0)
			(type default)
		)
	)
	(bus
		(pts
			(xy 266.7 185.42) (xy 266.7 200.66)
		)
		(stroke
			(width 0)
			(type default)
		)
	)
	(wire
		(pts
			(xy 153.67 67.31) (xy 153.67 64.77)
		)
		(stroke
			(width 0)
			(type default)
		)
	)
	(bus
		(pts
			(xy 99.06 116.84) (xy 99.06 119.38)
		)
		(stroke
			(width 0)
			(type default)
		)
	)
	(wire
		(pts
			(xy 265.43 201.93) (xy 248.92 201.93)
		)
		(stroke
			(width 0)
			(type default)
		)
	)
	(bus
		(pts
			(xy 152.4 165.1) (xy 152.4 175.26)
		)
		(stroke
			(width 0)
			(type default)
		)
	)
	(wire
		(pts
			(xy 130.81 57.15) (xy 138.43 57.15)
		)
		(stroke
			(width 0)
			(type default)
		)
	)
	(bus
		(pts
			(xy 149.86 80.01) (xy 95.25 80.01)
		)
		(stroke
			(width 0)
			(type default)
		)
	)
	(bus
		(pts
			(xy 99.06 165.1) (xy 99.06 170.18)
		)
		(stroke
			(width 0)
			(type default)
		)
	)
	(wire
		(pts
			(xy 265.43 186.69) (xy 248.92 186.69)
		)
		(stroke
			(width 0)
			(type default)
		)
	)
	(wire
		(pts
			(xy 257.81 67.31) (xy 265.43 67.31)
		)
		(stroke
			(width 0)
			(type default)
		)
	)
	(bus
		(pts
			(xy 266.7 119.38) (xy 266.7 121.92)
		)
		(stroke
			(width 0)
			(type default)
		)
	)
	(wire
		(pts
			(xy 152.4 118.11) (xy 149.86 118.11)
		)
		(stroke
			(width 0)
			(type default)
		)
	)
	(wire
		(pts
			(xy 130.81 67.31) (xy 138.43 67.31)
		)
		(stroke
			(width 0)
			(type default)
		)
	)
	(wire
		(pts
			(xy 138.43 64.77) (xy 138.43 67.31)
		)
		(stroke
			(width 0)
			(type default)
		)
	)
	(bus
		(pts
			(xy 152.4 187.96) (xy 152.4 190.5)
		)
		(stroke
			(width 0)
			(type default)
		)
	)
	(wire
		(pts
			(xy 129.54 97.79) (xy 127 97.79)
		)
		(stroke
			(width 0)
			(type default)
		)
	)
	(wire
		(pts
			(xy 179.07 179.07) (xy 153.67 179.07)
		)
		(stroke
			(width 0)
			(type default)
		)
	)
	(wire
		(pts
			(xy 265.43 113.03) (xy 248.92 113.03)
		)
		(stroke
			(width 0)
			(type default)
		)
	)
	(bus
		(pts
			(xy 266.7 132.08) (xy 266.7 134.62)
		)
		(stroke
			(width 0)
			(type default)
		)
	)
	(wire
		(pts
			(xy 265.43 166.37) (xy 248.92 166.37)
		)
		(stroke
			(width 0)
			(type default)
		)
	)
	(wire
		(pts
			(xy 265.43 176.53) (xy 248.92 176.53)
		)
		(stroke
			(width 0)
			(type default)
		)
	)
	(bus
		(pts
			(xy 152.4 193.04) (xy 152.4 195.58)
		)
		(stroke
			(width 0)
			(type default)
		)
	)
	(wire
		(pts
			(xy 138.43 57.15) (xy 138.43 59.69)
		)
		(stroke
			(width 0)
			(type default)
		)
	)
	(bus
		(pts
			(xy 266.7 129.54) (xy 266.7 132.08)
		)
		(stroke
			(width 0)
			(type default)
		)
	)
	(wire
		(pts
			(xy 250.19 57.15) (xy 257.81 57.15)
		)
		(stroke
			(width 0)
			(type default)
		)
	)
	(wire
		(pts
			(xy 295.91 67.31) (xy 295.91 64.77)
		)
		(stroke
			(width 0)
			(type default)
		)
	)
	(bus
		(pts
			(xy 266.7 111.76) (xy 266.7 116.84)
		)
		(stroke
			(width 0)
			(type default)
		)
	)
	(bus
		(pts
			(xy 151.13 81.28) (xy 149.86 80.01)
		)
		(stroke
			(width 0)
			(type default)
		)
	)
	(wire
		(pts
			(xy 179.07 214.63) (xy 153.67 214.63)
		)
		(stroke
			(width 0)
			(type default)
		)
	)
	(wire
		(pts
			(xy 265.43 173.99) (xy 248.92 173.99)
		)
		(stroke
			(width 0)
			(type default)
		)
	)
	(bus
		(pts
			(xy 266.7 203.2) (xy 266.7 213.36)
		)
		(stroke
			(width 0)
			(type default)
		)
	)
	(wire
		(pts
			(xy 179.07 110.49) (xy 100.33 110.49)
		)
		(stroke
			(width 0)
			(type default)
		)
	)
	(bus
		(pts
			(xy 152.4 134.62) (xy 152.4 137.16)
		)
		(stroke
			(width 0)
			(type default)
		)
	)
	(wire
		(pts
			(xy 110.49 203.2) (xy 110.49 205.74)
		)
		(stroke
			(width 0)
			(type default)
		)
	)
	(bus
		(pts
			(xy 152.4 182.88) (xy 152.4 185.42)
		)
		(stroke
			(width 0)
			(type default)
		)
	)
	(bus
		(pts
			(xy 266.7 139.7) (xy 266.7 142.24)
		)
		(stroke
			(width 0)
			(type default)
		)
	)
	(wire
		(pts
			(xy 179.07 140.97) (xy 153.67 140.97)
		)
		(stroke
			(width 0)
			(type default)
		)
	)
	(bus
		(pts
			(xy 152.4 157.48) (xy 152.4 160.02)
		)
		(stroke
			(width 0)
			(type default)
		)
	)
	(wire
		(pts
			(xy 179.07 166.37) (xy 100.33 166.37)
		)
		(stroke
			(width 0)
			(type default)
		)
	)
	(wire
		(pts
			(xy 110.49 203.2) (xy 100.33 203.2)
		)
		(stroke
			(width 0)
			(type default)
		)
	)
	(wire
		(pts
			(xy 265.43 179.07) (xy 248.92 179.07)
		)
		(stroke
			(width 0)
			(type default)
		)
	)
	(bus
		(pts
			(xy 152.4 139.7) (xy 152.4 142.24)
		)
		(stroke
			(width 0)
			(type default)
		)
	)
	(bus
		(pts
			(xy 127 83.82) (xy 95.25 83.82)
		)
		(stroke
			(width 0)
			(type default)
		)
	)
	(wire
		(pts
			(xy 106.68 57.15) (xy 123.19 57.15)
		)
		(stroke
			(width 0)
			(type default)
		)
	)
	(wire
		(pts
			(xy 265.43 146.05) (xy 248.92 146.05)
		)
		(stroke
			(width 0)
			(type default)
		)
	)
	(wire
		(pts
			(xy 168.91 57.15) (xy 177.8 57.15)
		)
		(stroke
			(width 0)
			(type default)
		)
	)
	(wire
		(pts
			(xy 295.91 67.31) (xy 288.29 67.31)
		)
		(stroke
			(width 0)
			(type default)
		)
	)
	(bus
		(pts
			(xy 151.13 101.6) (xy 151.13 111.76)
		)
		(stroke
			(width 0)
			(type default)
		)
	)
	(bus
		(pts
			(xy 152.4 160.02) (xy 152.4 162.56)
		)
		(stroke
			(width 0)
			(type default)
		)
	)
	(wire
		(pts
			(xy 179.07 143.51) (xy 153.67 143.51)
		)
		(stroke
			(width 0)
			(type default)
		)
	)
	(wire
		(pts
			(xy 146.05 67.31) (xy 146.05 64.77)
		)
		(stroke
			(width 0)
			(type default)
		)
	)
	(bus
		(pts
			(xy 128.27 85.09) (xy 128.27 91.44)
		)
		(stroke
			(width 0)
			(type default)
		)
	)
	(bus
		(pts
			(xy 152.4 185.42) (xy 152.4 187.96)
		)
		(stroke
			(width 0)
			(type default)
		)
	)
	(wire
		(pts
			(xy 303.53 67.31) (xy 303.53 68.58)
		)
		(stroke
			(width 0)
			(type default)
		)
	)
	(bus
		(pts
			(xy 152.4 129.54) (xy 152.4 132.08)
		)
		(stroke
			(width 0)
			(type default)
		)
	)
	(bus
		(pts
			(xy 266.7 149.86) (xy 266.7 154.94)
		)
		(stroke
			(width 0)
			(type default)
		)
	)
	(bus
		(pts
			(xy 152.4 154.94) (xy 152.4 157.48)
		)
		(stroke
			(width 0)
			(type default)
		)
	)
	(bus
		(pts
			(xy 152.4 162.56) (xy 152.4 165.1)
		)
		(stroke
			(width 0)
			(type default)
		)
	)
	(wire
		(pts
			(xy 303.53 64.77) (xy 303.53 67.31)
		)
		(stroke
			(width 0)
			(type default)
		)
	)
	(wire
		(pts
			(xy 161.29 64.77) (xy 161.29 67.31)
		)
		(stroke
			(width 0)
			(type default)
		)
	)
	(wire
		(pts
			(xy 179.07 133.35) (xy 153.67 133.35)
		)
		(stroke
			(width 0)
			(type default)
		)
	)
	(bus
		(pts
			(xy 266.7 147.32) (xy 266.7 149.86)
		)
		(stroke
			(width 0)
			(type default)
		)
	)
	(bus
		(pts
			(xy 152.4 137.16) (xy 152.4 139.7)
		)
		(stroke
			(width 0)
			(type default)
		)
	)
	(bus
		(pts
			(xy 293.37 87.63) (xy 267.97 87.63)
		)
		(stroke
			(width 0)
			(type default)
		)
	)
	(bus
		(pts
			(xy 99.06 114.3) (xy 99.06 116.84)
		)
		(stroke
			(width 0)
			(type default)
		)
	)
	(wire
		(pts
			(xy 179.07 181.61) (xy 153.67 181.61)
		)
		(stroke
			(width 0)
			(type default)
		)
	)
	(wire
		(pts
			(xy 273.05 67.31) (xy 280.67 67.31)
		)
		(stroke
			(width 0)
			(type default)
		)
	)
	(wire
		(pts
			(xy 179.07 173.99) (xy 153.67 173.99)
		)
		(stroke
			(width 0)
			(type default)
		)
	)
	(bus
		(pts
			(xy 128.27 96.52) (xy 128.27 106.68)
		)
		(stroke
			(width 0)
			(type default)
		)
	)
	(bus
		(pts
			(xy 266.7 154.94) (xy 266.7 160.02)
		)
		(stroke
			(width 0)
			(type default)
		)
	)
	(wire
		(pts
			(xy 161.29 57.15) (xy 161.29 59.69)
		)
		(stroke
			(width 0)
			(type default)
		)
	)
	(wire
		(pts
			(xy 168.91 67.31) (xy 168.91 64.77)
		)
		(stroke
			(width 0)
			(type default)
		)
	)
	(bus
		(pts
			(xy 152.4 203.2) (xy 152.4 210.82)
		)
		(stroke
			(width 0)
			(type default)
		)
	)
	(wire
		(pts
			(xy 265.43 140.97) (xy 248.92 140.97)
		)
		(stroke
			(width 0)
			(type default)
		)
	)
	(bus
		(pts
			(xy 99.06 111.76) (xy 99.06 114.3)
		)
		(stroke
			(width 0)
			(type default)
		)
	)
	(wire
		(pts
			(xy 265.43 118.11) (xy 248.92 118.11)
		)
		(stroke
			(width 0)
			(type default)
		)
	)
	(wire
		(pts
			(xy 265.43 148.59) (xy 248.92 148.59)
		)
		(stroke
			(width 0)
			(type default)
		)
	)
	(wire
		(pts
			(xy 152.4 115.57) (xy 149.86 115.57)
		)
		(stroke
			(width 0)
			(type default)
		)
	)
	(wire
		(pts
			(xy 265.43 204.47) (xy 248.92 204.47)
		)
		(stroke
			(width 0)
			(type default)
		)
	)
	(bus
		(pts
			(xy 266.7 109.22) (xy 266.7 111.76)
		)
		(stroke
			(width 0)
			(type default)
		)
	)
	(wire
		(pts
			(xy 179.07 113.03) (xy 152.4 113.03)
		)
		(stroke
			(width 0)
			(type default)
		)
	)
	(bus
		(pts
			(xy 97.79 87.63) (xy 95.25 87.63)
		)
		(stroke
			(width 0)
			(type default)
		)
	)
	(wire
		(pts
			(xy 265.43 138.43) (xy 248.92 138.43)
		)
		(stroke
			(width 0)
			(type default)
		)
	)
	(bus
		(pts
			(xy 152.4 215.9) (xy 152.4 224.79)
		)
		(stroke
			(width 0)
			(type default)
		)
	)
	(bus
		(pts
			(xy 152.4 177.8) (xy 152.4 180.34)
		)
		(stroke
			(width 0)
			(type default)
		)
	)
	(wire
		(pts
			(xy 129.54 95.25) (xy 127 95.25)
		)
		(stroke
			(width 0)
			(type default)
		)
	)
	(wire
		(pts
			(xy 123.19 120.65) (xy 100.33 120.65)
		)
		(stroke
			(width 0)
			(type default)
		)
	)
	(wire
		(pts
			(xy 179.07 196.85) (xy 153.67 196.85)
		)
		(stroke
			(width 0)
			(type default)
		)
	)
	(wire
		(pts
			(xy 303.53 67.31) (xy 295.91 67.31)
		)
		(stroke
			(width 0)
			(type default)
		)
	)
	(wire
		(pts
			(xy 179.07 92.71) (xy 129.54 92.71)
		)
		(stroke
			(width 0)
			(type default)
		)
	)
	(wire
		(pts
			(xy 265.43 120.65) (xy 248.92 120.65)
		)
		(stroke
			(width 0)
			(type default)
		)
	)
	(wire
		(pts
			(xy 288.29 57.15) (xy 280.67 57.15)
		)
		(stroke
			(width 0)
			(type default)
		)
	)
	(wire
		(pts
			(xy 265.43 64.77) (xy 265.43 67.31)
		)
		(stroke
			(width 0)
			(type default)
		)
	)
	(bus
		(pts
			(xy 151.13 226.06) (xy 152.4 224.79)
		)
		(stroke
			(width 0)
			(type default)
		)
	)
	(wire
		(pts
			(xy 265.43 130.81) (xy 248.92 130.81)
		)
		(stroke
			(width 0)
			(type default)
		)
	)
	(wire
		(pts
			(xy 265.43 57.15) (xy 265.43 59.69)
		)
		(stroke
			(width 0)
			(type default)
		)
	)
	(wire
		(pts
			(xy 179.07 171.45) (xy 100.33 171.45)
		)
		(stroke
			(width 0)
			(type default)
		)
	)
	(wire
		(pts
			(xy 153.67 57.15) (xy 153.67 59.69)
		)
		(stroke
			(width 0)
			(type default)
		)
	)
	(wire
		(pts
			(xy 146.05 102.87) (xy 100.33 102.87)
		)
		(stroke
			(width 0)
			(type default)
		)
	)
	(wire
		(pts
			(xy 130.81 67.31) (xy 130.81 64.77)
		)
		(stroke
			(width 0)
			(type default)
		)
	)
	(wire
		(pts
			(xy 250.19 88.9) (xy 248.92 88.9)
		)
		(stroke
			(width 0)
			(type default)
		)
	)
	(bus
		(pts
			(xy 152.4 195.58) (xy 152.4 198.12)
		)
		(stroke
			(width 0)
			(type default)
		)
	)
	(wire
		(pts
			(xy 123.19 64.77) (xy 123.19 67.31)
		)
		(stroke
			(width 0)
			(type default)
		)
	)
	(wire
		(pts
			(xy 179.07 123.19) (xy 153.67 123.19)
		)
		(stroke
			(width 0)
			(type default)
		)
	)
	(wire
		(pts
			(xy 265.43 161.29) (xy 248.92 161.29)
		)
		(stroke
			(width 0)
			(type default)
		)
	)
	(wire
		(pts
			(xy 179.07 125.73) (xy 153.67 125.73)
		)
		(stroke
			(width 0)
			(type default)
		)
	)
	(bus
		(pts
			(xy 266.7 116.84) (xy 266.7 119.38)
		)
		(stroke
			(width 0)
			(type default)
		)
	)
	(bus
		(pts
			(xy 152.4 144.78) (xy 152.4 147.32)
		)
		(stroke
			(width 0)
			(type default)
		)
	)
	(wire
		(pts
			(xy 168.91 59.69) (xy 168.91 57.15)
		)
		(stroke
			(width 0)
			(type default)
		)
	)
	(wire
		(pts
			(xy 179.07 105.41) (xy 163.83 105.41)
		)
		(stroke
			(width 0)
			(type default)
		)
	)
	(wire
		(pts
			(xy 153.67 57.15) (xy 161.29 57.15)
		)
		(stroke
			(width 0)
			(type default)
		)
	)
	(wire
		(pts
			(xy 179.07 115.57) (xy 152.4 115.57)
		)
		(stroke
			(width 0)
			(type default)
		)
	)
	(wire
		(pts
			(xy 153.67 67.31) (xy 146.05 67.31)
		)
		(stroke
			(width 0)
			(type default)
		)
	)
	(wire
		(pts
			(xy 138.43 57.15) (xy 146.05 57.15)
		)
		(stroke
			(width 0)
			(type default)
		)
	)
	(bus
		(pts
			(xy 128.27 85.09) (xy 127 83.82)
		)
		(stroke
			(width 0)
			(type default)
		)
	)
	(wire
		(pts
			(xy 295.91 57.15) (xy 288.29 57.15)
		)
		(stroke
			(width 0)
			(type default)
		)
	)
	(wire
		(pts
			(xy 288.29 57.15) (xy 288.29 59.69)
		)
		(stroke
			(width 0)
			(type default)
		)
	)
	(bus
		(pts
			(xy 152.4 147.32) (xy 152.4 149.86)
		)
		(stroke
			(width 0)
			(type default)
		)
	)
	(bus
		(pts
			(xy 99.06 109.22) (xy 99.06 111.76)
		)
		(stroke
			(width 0)
			(type default)
		)
	)
	(wire
		(pts
			(xy 179.07 163.83) (xy 153.67 163.83)
		)
		(stroke
			(width 0)
			(type default)
		)
	)
	(wire
		(pts
			(xy 265.43 163.83) (xy 248.92 163.83)
		)
		(stroke
			(width 0)
			(type default)
		)
	)
	(wire
		(pts
			(xy 288.29 64.77) (xy 288.29 67.31)
		)
		(stroke
			(width 0)
			(type default)
		)
	)
	(wire
		(pts
			(xy 179.07 118.11) (xy 152.4 118.11)
		)
		(stroke
			(width 0)
			(type default)
		)
	)
	(wire
		(pts
			(xy 179.07 128.27) (xy 153.67 128.27)
		)
		(stroke
			(width 0)
			(type default)
		)
	)
	(bus
		(pts
			(xy 152.4 152.4) (xy 152.4 154.94)
		)
		(stroke
			(width 0)
			(type default)
		)
	)
	(bus
		(pts
			(xy 266.7 88.9) (xy 266.7 91.44)
		)
		(stroke
			(width 0)
			(type default)
		)
	)
	(wire
		(pts
			(xy 280.67 59.69) (xy 280.67 57.15)
		)
		(stroke
			(width 0)
			(type default)
		)
	)
	(bus
		(pts
			(xy 152.4 142.24) (xy 152.4 144.78)
		)
		(stroke
			(width 0)
			(type default)
		)
	)
	(wire
		(pts
			(xy 273.05 67.31) (xy 273.05 64.77)
		)
		(stroke
			(width 0)
			(type default)
		)
	)
	(bus
		(pts
			(xy 128.27 91.44) (xy 128.27 93.98)
		)
		(stroke
			(width 0)
			(type default)
		)
	)
	(bus
		(pts
			(xy 266.7 172.72) (xy 266.7 175.26)
		)
		(stroke
			(width 0)
			(type default)
		)
	)
	(wire
		(pts
			(xy 273.05 57.15) (xy 273.05 59.69)
		)
		(stroke
			(width 0)
			(type default)
		)
	)
	(bus
		(pts
			(xy 266.7 142.24) (xy 266.7 144.78)
		)
		(stroke
			(width 0)
			(type default)
		)
	)
	(wire
		(pts
			(xy 179.07 153.67) (xy 153.67 153.67)
		)
		(stroke
			(width 0)
			(type default)
		)
	)
	(bus
		(pts
			(xy 266.7 144.78) (xy 266.7 147.32)
		)
		(stroke
			(width 0)
			(type default)
		)
	)
	(wire
		(pts
			(xy 265.43 135.89) (xy 248.92 135.89)
		)
		(stroke
			(width 0)
			(type default)
		)
	)
	(wire
		(pts
			(xy 265.43 128.27) (xy 248.92 128.27)
		)
		(stroke
			(width 0)
			(type default)
		)
	)
	(bus
		(pts
			(xy 128.27 93.98) (xy 128.27 96.52)
		)
		(stroke
			(width 0)
			(type default)
		)
	)
	(bus
		(pts
			(xy 266.7 124.46) (xy 266.7 127)
		)
		(stroke
			(width 0)
			(type default)
		)
	)
	(bus
		(pts
			(xy 266.7 91.44) (xy 266.7 109.22)
		)
		(stroke
			(width 0)
			(type default)
		)
	)
	(bus
		(pts
			(xy 266.7 200.66) (xy 266.7 203.2)
		)
		(stroke
			(width 0)
			(type default)
		)
	)
	(bus
		(pts
			(xy 266.7 170.18) (xy 266.7 172.72)
		)
		(stroke
			(width 0)
			(type default)
		)
	)
	(wire
		(pts
			(xy 146.05 59.69) (xy 146.05 57.15)
		)
		(stroke
			(width 0)
			(type default)
		)
	)
	(wire
		(pts
			(xy 179.07 209.55) (xy 153.67 209.55)
		)
		(stroke
			(width 0)
			(type default)
		)
	)
	(wire
		(pts
			(xy 179.07 212.09) (xy 153.67 212.09)
		)
		(stroke
			(width 0)
			(type default)
		)
	)
	(wire
		(pts
			(xy 280.67 67.31) (xy 280.67 64.77)
		)
		(stroke
			(width 0)
			(type default)
		)
	)
	(wire
		(pts
			(xy 265.43 123.19) (xy 248.92 123.19)
		)
		(stroke
			(width 0)
			(type default)
		)
	)
	(wire
		(pts
			(xy 146.05 118.11) (xy 100.33 118.11)
		)
		(stroke
			(width 0)
			(type default)
		)
	)
	(wire
		(pts
			(xy 179.07 135.89) (xy 153.67 135.89)
		)
		(stroke
			(width 0)
			(type default)
		)
	)
	(wire
		(pts
			(xy 106.68 55.88) (xy 106.68 57.15)
		)
		(stroke
			(width 0)
			(type default)
		)
	)
	(wire
		(pts
			(xy 265.43 184.15) (xy 248.92 184.15)
		)
		(stroke
			(width 0)
			(type default)
		)
	)
	(wire
		(pts
			(xy 146.05 115.57) (xy 100.33 115.57)
		)
		(stroke
			(width 0)
			(type default)
		)
	)
	(wire
		(pts
			(xy 129.54 120.65) (xy 127 120.65)
		)
		(stroke
			(width 0)
			(type default)
		)
	)
	(wire
		(pts
			(xy 123.19 57.15) (xy 123.19 59.69)
		)
		(stroke
			(width 0)
			(type default)
		)
	)
	(wire
		(pts
			(xy 100.33 97.79) (xy 123.19 97.79)
		)
		(stroke
			(width 0)
			(type default)
		)
	)
	(bus
		(pts
			(xy 151.13 111.76) (xy 151.13 114.3)
		)
		(stroke
			(width 0)
			(type default)
		)
	)
	(wire
		(pts
			(xy 280.67 67.31) (xy 288.29 67.31)
		)
		(stroke
			(width 0)
			(type default)
		)
	)
	(bus
		(pts
			(xy 152.4 124.46) (xy 152.4 127)
		)
		(stroke
			(width 0)
			(type default)
		)
	)
	(wire
		(pts
			(xy 179.07 156.21) (xy 153.67 156.21)
		)
		(stroke
			(width 0)
			(type default)
		)
	)
	(wire
		(pts
			(xy 179.07 120.65) (xy 129.54 120.65)
		)
		(stroke
			(width 0)
			(type default)
		)
	)
	(wire
		(pts
			(xy 273.05 57.15) (xy 265.43 57.15)
		)
		(stroke
			(width 0)
			(type default)
		)
	)
	(wire
		(pts
			(xy 265.43 143.51) (xy 248.92 143.51)
		)
		(stroke
			(width 0)
			(type default)
		)
	)
	(wire
		(pts
			(xy 130.81 57.15) (xy 130.81 59.69)
		)
		(stroke
			(width 0)
			(type default)
		)
	)
	(bus
		(pts
			(xy 266.7 167.64) (xy 266.7 170.18)
		)
		(stroke
			(width 0)
			(type default)
		)
	)
	(wire
		(pts
			(xy 123.19 67.31) (xy 123.19 68.58)
		)
		(stroke
			(width 0)
			(type default)
		)
	)
	(wire
		(pts
			(xy 320.04 54.61) (xy 320.04 57.15)
		)
		(stroke
			(width 0)
			(type default)
		)
	)
	(bus
		(pts
			(xy 152.4 175.26) (xy 152.4 177.8)
		)
		(stroke
			(width 0)
			(type default)
		)
	)
	(bus
		(pts
			(xy 266.7 160.02) (xy 266.7 162.56)
		)
		(stroke
			(width 0)
			(type default)
		)
	)
	(bus
		(pts
			(xy 99.06 101.6) (xy 99.06 109.22)
		)
		(stroke
			(width 0)
			(type default)
		)
	)
	(bus
		(pts
			(xy 266.7 182.88) (xy 266.7 185.42)
		)
		(stroke
			(width 0)
			(type default)
		)
	)
	(bus
		(pts
			(xy 266.7 121.92) (xy 266.7 124.46)
		)
		(stroke
			(width 0)
			(type default)
		)
	)
	(wire
		(pts
			(xy 179.07 151.13) (xy 153.67 151.13)
		)
		(stroke
			(width 0)
			(type default)
		)
	)
	(wire
		(pts
			(xy 265.43 168.91) (xy 248.92 168.91)
		)
		(stroke
			(width 0)
			(type default)
		)
	)
	(wire
		(pts
			(xy 179.07 189.23) (xy 153.67 189.23)
		)
		(stroke
			(width 0)
			(type default)
		)
	)
	(wire
		(pts
			(xy 265.43 214.63) (xy 248.92 214.63)
		)
		(stroke
			(width 0)
			(type default)
		)
	)
	(wire
		(pts
			(xy 320.04 57.15) (xy 303.53 57.15)
		)
		(stroke
			(width 0)
			(type default)
		)
	)
	(wire
		(pts
			(xy 265.43 151.13) (xy 248.92 151.13)
		)
		(stroke
			(width 0)
			(type default)
		)
	)
	(bus
		(pts
			(xy 152.4 213.36) (xy 152.4 215.9)
		)
		(stroke
			(width 0)
			(type default)
		)
	)
	(bus
		(pts
			(xy 266.7 162.56) (xy 266.7 165.1)
		)
		(stroke
			(width 0)
			(type default)
		)
	)
	(wire
		(pts
			(xy 265.43 133.35) (xy 248.92 133.35)
		)
		(stroke
			(width 0)
			(type default)
		)
	)
	(wire
		(pts
			(xy 179.07 158.75) (xy 153.67 158.75)
		)
		(stroke
			(width 0)
			(type default)
		)
	)
	(wire
		(pts
			(xy 265.43 110.49) (xy 248.92 110.49)
		)
		(stroke
			(width 0)
			(type default)
		)
	)
	(wire
		(pts
			(xy 295.91 57.15) (xy 295.91 59.69)
		)
		(stroke
			(width 0)
			(type default)
		)
	)
	(wire
		(pts
			(xy 100.33 95.25) (xy 123.19 95.25)
		)
		(stroke
			(width 0)
			(type default)
		)
	)
	(bus
		(pts
			(xy 152.4 180.34) (xy 152.4 182.88)
		)
		(stroke
			(width 0)
			(type default)
		)
	)
	(wire
		(pts
			(xy 179.07 201.93) (xy 153.67 201.93)
		)
		(stroke
			(width 0)
			(type default)
		)
	)
	(bus
		(pts
			(xy 128.27 106.68) (xy 128.27 119.38)
		)
		(stroke
			(width 0)
			(type default)
		)
	)
	(bus
		(pts
			(xy 152.4 200.66) (xy 152.4 203.2)
		)
		(stroke
			(width 0)
			(type default)
		)
	)
	(wire
		(pts
			(xy 179.07 199.39) (xy 153.67 199.39)
		)
		(stroke
			(width 0)
			(type default)
		)
	)
	(bus
		(pts
			(xy 266.7 177.8) (xy 266.7 182.88)
		)
		(stroke
			(width 0)
			(type default)
		)
	)
	(bus
		(pts
			(xy 266.7 175.26) (xy 266.7 177.8)
		)
		(stroke
			(width 0)
			(type default)
		)
	)
	(wire
		(pts
			(xy 152.4 102.87) (xy 149.86 102.87)
		)
		(stroke
			(width 0)
			(type default)
		)
	)
	(wire
		(pts
			(xy 179.07 184.15) (xy 153.67 184.15)
		)
		(stroke
			(width 0)
			(type default)
		)
	)
	(bus
		(pts
			(xy 152.4 127) (xy 152.4 129.54)
		)
		(stroke
			(width 0)
			(type default)
		)
	)
	(bus
		(pts
			(xy 99.06 88.9) (xy 97.79 87.63)
		)
		(stroke
			(width 0)
			(type default)
		)
	)
	(wire
		(pts
			(xy 179.07 138.43) (xy 153.67 138.43)
		)
		(stroke
			(width 0)
			(type default)
		)
	)
	(bus
		(pts
			(xy 266.7 137.16) (xy 266.7 139.7)
		)
		(stroke
			(width 0)
			(type default)
		)
	)
	(wire
		(pts
			(xy 161.29 57.15) (xy 168.91 57.15)
		)
		(stroke
			(width 0)
			(type default)
		)
	)
	(bus
		(pts
			(xy 151.13 114.3) (xy 151.13 116.84)
		)
		(stroke
			(width 0)
			(type default)
		)
	)
	(wire
		(pts
			(xy 179.07 146.05) (xy 153.67 146.05)
		)
		(stroke
			(width 0)
			(type default)
		)
	)
	(wire
		(pts
			(xy 129.54 97.79) (xy 179.07 97.79)
		)
		(stroke
			(width 0)
			(type default)
		)
	)
	(wire
		(pts
			(xy 123.19 57.15) (xy 130.81 57.15)
		)
		(stroke
			(width 0)
			(type default)
		)
	)
	(bus
		(pts
			(xy 152.4 132.08) (xy 152.4 134.62)
		)
		(stroke
			(width 0)
			(type default)
		)
	)
	(wire
		(pts
			(xy 179.07 107.95) (xy 129.54 107.95)
		)
		(stroke
			(width 0)
			(type default)
		)
	)
	(bus
		(pts
			(xy 266.7 127) (xy 266.7 129.54)
		)
		(stroke
			(width 0)
			(type default)
		)
	)
	(wire
		(pts
			(xy 265.43 67.31) (xy 273.05 67.31)
		)
		(stroke
			(width 0)
			(type default)
		)
	)
	(bus
		(pts
			(xy 152.4 190.5) (xy 152.4 193.04)
		)
		(stroke
			(width 0)
			(type default)
		)
	)
	(wire
		(pts
			(xy 280.67 57.15) (xy 273.05 57.15)
		)
		(stroke
			(width 0)
			(type default)
		)
	)
	(wire
		(pts
			(xy 179.07 194.31) (xy 153.67 194.31)
		)
		(stroke
			(width 0)
			(type default)
		)
	)
	(wire
		(pts
			(xy 179.07 100.33) (xy 100.33 100.33)
		)
		(stroke
			(width 0)
			(type default)
		)
	)
	(wire
		(pts
			(xy 179.07 148.59) (xy 153.67 148.59)
		)
		(stroke
			(width 0)
			(type default)
		)
	)
	(bus
		(pts
			(xy 99.06 96.52) (xy 99.06 99.06)
		)
		(stroke
			(width 0)
			(type default)
		)
	)
	(wire
		(pts
			(xy 265.43 125.73) (xy 248.92 125.73)
		)
		(stroke
			(width 0)
			(type default)
		)
	)
	(bus
		(pts
			(xy 99.06 119.38) (xy 99.06 165.1)
		)
		(stroke
			(width 0)
			(type default)
		)
	)
	(wire
		(pts
			(xy 179.07 102.87) (xy 152.4 102.87)
		)
		(stroke
			(width 0)
			(type default)
		)
	)
	(wire
		(pts
			(xy 179.07 88.9) (xy 177.8 88.9)
		)
		(stroke
			(width 0)
			(type default)
		)
	)
	(wire
		(pts
			(xy 179.07 186.69) (xy 153.67 186.69)
		)
		(stroke
			(width 0)
			(type default)
		)
	)
	(wire
		(pts
			(xy 257.81 59.69) (xy 257.81 57.15)
		)
		(stroke
			(width 0)
			(type default)
		)
	)
	(wire
		(pts
			(xy 161.29 67.31) (xy 153.67 67.31)
		)
		(stroke
			(width 0)
			(type default)
		)
	)
	(label "USER_IO.A17"
		(at 251.46 143.51 0)
		(effects
			(font
				(size 1.27 1.27)
			)
			(justify left bottom)
		)
	)
	(label "SUP_MCU.SPARE3"
		(at 121.92 110.49 180)
		(effects
			(font
				(size 1.27 1.27)
			)
			(justify right bottom)
		)
	)
	(label "USER_IO.A21"
		(at 251.46 173.99 0)
		(effects
			(font
				(size 1.27 1.27)
			)
			(justify left bottom)
		)
	)
	(label "SRAM.DQ4"
		(at 177.8 123.19 180)
		(effects
			(font
				(size 1.27 1.27)
			)
			(justify right bottom)
		)
	)
	(label "USER_IO.A33"
		(at 251.46 163.83 0)
		(effects
			(font
				(size 1.27 1.27)
			)
			(justify left bottom)
		)
	)
	(label "SYSTEM_FLASH.~{CS}"
		(at 148.59 120.65 180)
		(effects
			(font
				(size 1.27 1.27)
			)
			(justify right bottom)
		)
	)
	(label "SRAM.A9"
		(at 177.8 135.89 180)
		(effects
			(font
				(size 1.27 1.27)
			)
			(justify right bottom)
		)
	)
	(label "SUP_MCU.SCLK1"
		(at 121.92 100.33 180)
		(effects
			(font
				(size 1.27 1.27)
			)
			(justify right bottom)
		)
	)
	(label "SUP_MCU.SCLK0"
		(at 121.92 115.57 180)
		(effects
			(font
				(size 1.27 1.27)
			)
			(justify right bottom)
		)
	)
	(label "SRAM.A3"
		(at 177.8 151.13 180)
		(effects
			(font
				(size 1.27 1.27)
			)
			(justify right bottom)
		)
	)
	(label "USER_IO.A13"
		(at 251.46 128.27 0)
		(effects
			(font
				(size 1.27 1.27)
			)
			(justify left bottom)
		)
	)
	(label "USER_IO.A28"
		(at 251.46 168.91 0)
		(effects
			(font
				(size 1.27 1.27)
			)
			(justify left bottom)
		)
	)
	(label "SRAM.A16"
		(at 176.53 191.77 180)
		(effects
			(font
				(size 1.27 1.27)
			)
			(justify right bottom)
		)
	)
	(label "SYSTEM_FLASH.DQ3"
		(at 148.59 107.95 180)
		(effects
			(font
				(size 1.27 1.27)
			)
			(justify right bottom)
		)
	)
	(label "USB_SPI.~{CS}"
		(at 177.8 118.11 180)
		(effects
			(font
				(size 1.27 1.27)
			)
			(justify right bottom)
		)
	)
	(label "SRAM.DQ6"
		(at 177.8 146.05 180)
		(effects
			(font
				(size 1.27 1.27)
			)
			(justify right bottom)
		)
	)
	(label "USER_IO.A16"
		(at 251.46 120.65 0)
		(effects
			(font
				(size 1.27 1.27)
			)
			(justify left bottom)
		)
	)
	(label "SUP_MCU.FPGA_MISO"
		(at 121.92 95.25 180)
		(effects
			(font
				(size 1.27 1.27)
			)
			(justify right bottom)
		)
	)
	(label "SRAM.A7"
		(at 176.53 209.55 180)
		(effects
			(font
				(size 1.27 1.27)
			)
			(justify right bottom)
		)
	)
	(label "SRAM.A15"
		(at 177.8 138.43 180)
		(effects
			(font
				(size 1.27 1.27)
			)
			(justify right bottom)
		)
	)
	(label "SRAM.DQ3"
		(at 177.8 125.73 180)
		(effects
			(font
				(size 1.27 1.27)
			)
			(justify right bottom)
		)
	)
	(label "SRAM.A5"
		(at 177.8 130.81 180)
		(effects
			(font
				(size 1.27 1.27)
			)
			(justify right bottom)
		)
	)
	(label "USER_IO.A39"
		(at 251.46 140.97 0)
		(effects
			(font
				(size 1.27 1.27)
			)
			(justify left bottom)
		)
	)
	(label "USER_IO.A9"
		(at 251.46 125.73 0)
		(effects
			(font
				(size 1.27 1.27)
			)
			(justify left bottom)
		)
	)
	(label "SUP_MCU.SPARE1"
		(at 121.92 171.45 180)
		(effects
			(font
				(size 1.27 1.27)
			)
			(justify right bottom)
		)
	)
	(label "SRAM.~{CE}"
		(at 176.53 173.99 180)
		(effects
			(font
				(size 1.27 1.27)
			)
			(justify right bottom)
		)
	)
	(label "USER_IO.A25"
		(at 251.46 110.49 0)
		(effects
			(font
				(size 1.27 1.27)
			)
			(justify left bottom)
		)
	)
	(label "SRAM.~{WE}"
		(at 176.53 214.63 180)
		(effects
			(font
				(size 1.27 1.27)
			)
			(justify right bottom)
		)
	)
	(label "USB_SPI.MOSI"
		(at 177.8 113.03 180)
		(effects
			(font
				(size 1.27 1.27)
			)
			(justify right bottom)
		)
	)
	(label "USB_SPI.SCK"
		(at 177.8 115.57 180)
		(effects
			(font
				(size 1.27 1.27)
			)
			(justify right bottom)
		)
	)
	(label "SRAM.A1"
		(at 176.53 176.53 180)
		(effects
			(font
				(size 1.27 1.27)
			)
			(justify right bottom)
		)
	)
	(label "SRAM.A2"
		(at 177.8 161.29 180)
		(effects
			(font
				(size 1.27 1.27)
			)
			(justify right bottom)
		)
	)
	(label "USER_IO.A14"
		(at 251.46 133.35 0)
		(effects
			(font
				(size 1.27 1.27)
			)
			(justify left bottom)
		)
	)
	(label "USER_IO.A23"
		(at 251.46 166.37 0)
		(effects
			(font
				(size 1.27 1.27)
			)
			(justify left bottom)
		)
	)
	(label "SRAM.A12"
		(at 176.53 186.69 180)
		(effects
			(font
				(size 1.27 1.27)
			)
			(justify right bottom)
		)
	)
	(label "SRAM.DQ0"
		(at 176.53 201.93 180)
		(effects
			(font
				(size 1.27 1.27)
			)
			(justify right bottom)
		)
	)
	(label "USER_IO.A1"
		(at 251.46 92.71 0)
		(effects
			(font
				(size 1.27 1.27)
			)
			(justify left bottom)
		)
	)
	(label "SRAM.A17"
		(at 176.53 194.31 180)
		(effects
			(font
				(size 1.27 1.27)
			)
			(justify right bottom)
		)
	)
	(label "SRAM.CE2"
		(at 176.53 196.85 180)
		(effects
			(font
				(size 1.27 1.27)
			)
			(justify right bottom)
		)
	)
	(label "USER_IO.A12"
		(at 251.46 130.81 0)
		(effects
			(font
				(size 1.27 1.27)
			)
			(justify left bottom)
		)
	)
	(label "USER_IO.A24"
		(at 251.46 179.07 0)
		(effects
			(font
				(size 1.27 1.27)
			)
			(justify left bottom)
		)
	)
	(label "USER_IO.A5"
		(at 251.46 201.93 0)
		(effects
			(font
				(size 1.27 1.27)
			)
			(justify left bottom)
		)
	)
	(label "SUP_MCU.MOSI"
		(at 121.92 113.03 180)
		(effects
			(font
				(size 1.27 1.27)
			)
			(justify right bottom)
		)
	)
	(label "USER_IO.A37"
		(at 251.46 148.59 0)
		(effects
			(font
				(size 1.27 1.27)
			)
			(justify left bottom)
		)
	)
	(label "SUP_MCU.SPARE2"
		(at 121.92 166.37 180)
		(effects
			(font
				(size 1.27 1.27)
			)
			(justify right bottom)
		)
	)
	(label "SRAM.~{OE}"
		(at 177.8 140.97 180)
		(effects
			(font
				(size 1.27 1.27)
			)
			(justify right bottom)
		)
	)
	(label "USER_IO.A7"
		(at 251.46 138.43 0)
		(effects
			(font
				(size 1.27 1.27)
			)
			(justify left bottom)
		)
	)
	(label "USER_IO.A31"
		(at 251.46 146.05 0)
		(effects
			(font
				(size 1.27 1.27)
			)
			(justify left bottom)
		)
	)
	(label "USER_IO.A35"
		(at 251.46 151.13 0)
		(effects
			(font
				(size 1.27 1.27)
			)
			(justify left bottom)
		)
	)
	(label "USER_IO.A26"
		(at 251.46 118.11 0)
		(effects
			(font
				(size 1.27 1.27)
			)
			(justify left bottom)
		)
	)
	(label "SRAM.A11"
		(at 177.8 163.83 180)
		(effects
			(font
				(size 1.27 1.27)
			)
			(justify right bottom)
		)
	)
	(label "SYSTEM_FLASH.DQ0"
		(at 148.59 95.25 180)
		(effects
			(font
				(size 1.27 1.27)
			)
			(justify right bottom)
		)
	)
	(label "USER_IO.A15"
		(at 251.46 186.69 0)
		(effects
			(font
				(size 1.27 1.27)
			)
			(justify left bottom)
		)
	)
	(label "USER_IO.A38"
		(at 251.46 184.15 0)
		(effects
			(font
				(size 1.27 1.27)
			)
			(justify left bottom)
		)
	)
	(label "USER_IO.A3"
		(at 251.46 135.89 0)
		(effects
			(font
				(size 1.27 1.27)
			)
			(justify left bottom)
		)
	)
	(label "SRAM.DQ2"
		(at 176.53 212.09 180)
		(effects
			(font
				(size 1.27 1.27)
			)
			(justify right bottom)
		)
	)
	(label "SRAM.A19"
		(at 176.53 184.15 180)
		(effects
			(font
				(size 1.27 1.27)
			)
			(justify right bottom)
		)
	)
	(label "SRAM.DQ5"
		(at 177.8 148.59 180)
		(effects
			(font
				(size 1.27 1.27)
			)
			(justify right bottom)
		)
	)
	(label "SRAM.A10"
		(at 177.8 156.21 180)
		(effects
			(font
				(size 1.27 1.27)
			)
			(justify right bottom)
		)
	)
	(label "USER_IO.A18"
		(at 251.46 123.19 0)
		(effects
			(font
				(size 1.27 1.27)
			)
			(justify left bottom)
		)
	)
	(label "SRAM.A14"
		(at 176.53 199.39 180)
		(effects
			(font
				(size 1.27 1.27)
			)
			(justify right bottom)
		)
	)
	(label "SRAM.A4"
		(at 176.53 189.23 180)
		(effects
			(font
				(size 1.27 1.27)
			)
			(justify right bottom)
		)
	)
	(label "SUP_MCU.FPGA_MOSI"
		(at 121.92 97.79 180)
		(effects
			(font
				(size 1.27 1.27)
			)
			(justify right bottom)
		)
	)
	(label "USER_IO.A40"
		(at 251.46 113.03 0)
		(effects
			(font
				(size 1.27 1.27)
			)
			(justify left bottom)
		)
	)
	(label "SRAM.DQ7"
		(at 177.8 128.27 180)
		(effects
			(font
				(size 1.27 1.27)
			)
			(justify right bottom)
		)
	)
	(label "USER_IO.A36"
		(at 251.46 176.53 0)
		(effects
			(font
				(size 1.27 1.27)
			)
			(justify left bottom)
		)
	)
	(label "SRAM.A18"
		(at 176.53 181.61 180)
		(effects
			(font
				(size 1.27 1.27)
			)
			(justify right bottom)
		)
	)
	(label "SYSTEM_FLASH.DQ2"
		(at 148.59 92.71 180)
		(effects
			(font
				(size 1.27 1.27)
			)
			(justify right bottom)
		)
	)
	(label "SRAM.A0"
		(at 177.8 158.75 180)
		(effects
			(font
				(size 1.27 1.27)
			)
			(justify right bottom)
		)
	)
	(label "SRAM.A6"
		(at 177.8 133.35 180)
		(effects
			(font
				(size 1.27 1.27)
			)
			(justify right bottom)
		)
	)
	(label "SUP_MCU.CFG_CS"
		(at 121.92 120.65 180)
		(effects
			(font
				(size 1.27 1.27)
			)
			(justify right bottom)
		)
	)
	(label "SUP_MCU.MISO"
		(at 121.92 102.87 180)
		(effects
			(font
				(size 1.27 1.27)
			)
			(justify right bottom)
		)
	)
	(label "SYSTEM_FLASH.DQ1"
		(at 148.59 97.79 180)
		(effects
			(font
				(size 1.27 1.27)
			)
			(justify right bottom)
		)
	)
	(label "SRAM.A13"
		(at 177.8 153.67 180)
		(effects
			(font
				(size 1.27 1.27)
			)
			(justify right bottom)
		)
	)
	(label "CFG_PUDC"
		(at 100.33 203.2 0)
		(effects
			(font
				(size 1.27 1.27)
			)
			(justify left bottom)
		)
	)
	(label "USER_IO.A30"
		(at 251.46 171.45 0)
		(effects
			(font
				(size 1.27 1.27)
			)
			(justify left bottom)
		)
	)
	(label "USER_IO.A27"
		(at 251.46 204.47 0)
		(effects
			(font
				(size 1.27 1.27)
			)
			(justify left bottom)
		)
	)
	(label "SRAM.DQ1"
		(at 176.53 179.07 180)
		(effects
			(font
				(size 1.27 1.27)
			)
			(justify right bottom)
		)
	)
	(label "USB_SPI.MISO"
		(at 177.8 102.87 180)
		(effects
			(font
				(size 1.27 1.27)
			)
			(justify right bottom)
		)
	)
	(label "USER_IO.A29"
		(at 251.46 214.63 0)
		(effects
			(font
				(size 1.27 1.27)
			)
			(justify left bottom)
		)
	)
	(label "USER_IO.A32"
		(at 251.46 156.21 0)
		(effects
			(font
				(size 1.27 1.27)
			)
			(justify left bottom)
		)
	)
	(label "USER_IO.A11"
		(at 251.46 161.29 0)
		(effects
			(font
				(size 1.27 1.27)
			)
			(justify left bottom)
		)
	)
	(label "SUP_MCU.~{SCS}"
		(at 121.92 118.11 180)
		(effects
			(font
				(size 1.27 1.27)
			)
			(justify right bottom)
		)
	)
	(label "SRAM.A8"
		(at 177.8 143.51 180)
		(effects
			(font
				(size 1.27 1.27)
			)
			(justify right bottom)
		)
	)
	(label "CFG_PUDC"
		(at 163.83 105.41 0)
		(effects
			(font
				(size 1.27 1.27)
			)
			(justify left bottom)
		)
	)
	(hierarchical_label "SRAM{SRAM}"
		(shape input)
		(at 95.25 226.06 180)
		(effects
			(font
				(size 1.27 1.27)
			)
			(justify right)
		)
	)
	(hierarchical_label "USB_SPI{SPI}"
		(shape bidirectional)
		(at 95.25 80.01 180)
		(effects
			(font
				(size 1.27 1.27)
			)
			(justify right)
		)
	)
	(hierarchical_label "USER_IO{USER-IO}"
		(shape bidirectional)
		(at 293.37 87.63 0)
		(effects
			(font
				(size 1.27 1.27)
			)
			(justify left)
		)
	)
	(hierarchical_label "SUP_MCU{SUP-MCU}"
		(shape bidirectional)
		(at 95.25 87.63 180)
		(effects
			(font
				(size 1.27 1.27)
			)
			(justify right)
		)
	)
	(hierarchical_label "SYSTEM_FLASH{SPI-FLASH}"
		(shape bidirectional)
		(at 95.25 83.82 180)
		(effects
			(font
				(size 1.27 1.27)
			)
			(justify right)
		)
	)
	(symbol
		(lib_id "k410t-devboard:Net-Tie_2")
		(at 149.86 115.57 0)
		(mirror y)
		(unit 1)
		(exclude_from_sim no)
		(in_bom yes)
		(on_board yes)
		(dnp no)
		(property "Reference" "NT11"
			(at 149.86 114.3 0)
			(effects
				(font
					(size 1.27 1.27)
				)
				(hide yes)
			)
		)
		(property "Value" "Net-Tie_2"
			(at 149.225 114.935 0)
			(effects
				(font
					(size 1.27 1.27)
					(thickness 0.15)
				)
				(justify left bottom)
				(hide yes)
			)
		)
		(property "Footprint" "antmicro-footprints:NetTie-2_SMD_Pad0.127mm"
			(at 128.27 120.65 0)
			(effects
				(font
					(size 1.27 1.27)
					(thickness 0.15)
				)
				(justify left bottom)
				(hide yes)
			)
		)
		(property "Datasheet" ""
			(at 128.27 123.19 0)
			(effects
				(font
					(size 1.27 1.27)
					(thickness 0.15)
				)
				(justify left bottom)
				(hide yes)
			)
		)
		(property "Description" ""
			(at 149.86 115.57 0)
			(effects
				(font
					(size 1.27 1.27)
				)
			)
		)
		(property "MPN" ""
			(at 128.27 124.46 0)
			(effects
				(font
					(size 1.27 1.27)
				)
				(justify left)
				(hide yes)
			)
		)
		(property "Manufacturer" ""
			(at 128.27 127 0)
			(effects
				(font
					(size 1.27 1.27)
				)
				(justify left)
				(hide yes)
			)
		)
		(property "Author" "Antmicro"
			(at 128.27 130.81 0)
			(effects
				(font
					(size 1.27 1.27)
					(thickness 0.15)
				)
				(justify left bottom)
				(hide yes)
			)
		)
		(property "License" "Apache-2.0"
			(at 128.27 133.35 0)
			(effects
				(font
					(size 1.27 1.27)
					(thickness 0.15)
				)
				(justify left bottom)
				(hide yes)
			)
		)
		(pin "1"
		)
		(pin "2"
		)
		(instances
			(project "k410t-devboard"
				(path ""
					(reference "NT11")
					(unit 1)
				)
			)
		)
	)
	(symbol
		(lib_id "k410t-devboard:Net-Tie_2")
		(at 149.86 102.87 0)
		(mirror y)
		(unit 1)
		(exclude_from_sim no)
		(in_bom yes)
		(on_board yes)
		(dnp no)
		(property "Reference" "NT9"
			(at 149.86 101.6 0)
			(effects
				(font
					(size 1.27 1.27)
				)
				(hide yes)
			)
		)
		(property "Value" "Net-Tie_2"
			(at 149.225 102.235 0)
			(effects
				(font
					(size 1.27 1.27)
					(thickness 0.15)
				)
				(justify left bottom)
				(hide yes)
			)
		)
		(property "Footprint" "antmicro-footprints:NetTie-2_SMD_Pad0.127mm"
			(at 128.27 107.95 0)
			(effects
				(font
					(size 1.27 1.27)
					(thickness 0.15)
				)
				(justify left bottom)
				(hide yes)
			)
		)
		(property "Datasheet" ""
			(at 128.27 110.49 0)
			(effects
				(font
					(size 1.27 1.27)
					(thickness 0.15)
				)
				(justify left bottom)
				(hide yes)
			)
		)
		(property "Description" ""
			(at 149.86 102.87 0)
			(effects
				(font
					(size 1.27 1.27)
				)
			)
		)
		(property "MPN" ""
			(at 128.27 111.76 0)
			(effects
				(font
					(size 1.27 1.27)
				)
				(justify left)
				(hide yes)
			)
		)
		(property "Manufacturer" ""
			(at 128.27 114.3 0)
			(effects
				(font
					(size 1.27 1.27)
				)
				(justify left)
				(hide yes)
			)
		)
		(property "Author" "Antmicro"
			(at 128.27 118.11 0)
			(effects
				(font
					(size 1.27 1.27)
					(thickness 0.15)
				)
				(justify left bottom)
				(hide yes)
			)
		)
		(property "License" "Apache-2.0"
			(at 128.27 120.65 0)
			(effects
				(font
					(size 1.27 1.27)
					(thickness 0.15)
				)
				(justify left bottom)
				(hide yes)
			)
		)
		(pin "1"
		)
		(pin "2"
		)
		(instances
			(project "k410t-devboard"
				(path ""
					(reference "NT9")
					(unit 1)
				)
			)
		)
	)
	(symbol
		(lib_id "antmicroCapacitors0402:C_100n_0402")
		(at 161.29 64.77 90)
		(unit 1)
		(exclude_from_sim no)
		(in_bom yes)
		(on_board yes)
		(dnp no)
		(property "Reference" "C37"
			(at 162.56 59.69 90)
			(effects
				(font
					(size 1.27 1.27)
				)
				(justify right)
			)
		)
		(property "Value" "C_100n_0402"
			(at 171.45 44.45 0)
			(effects
				(font
					(size 1.27 1.27)
					(thickness 0.15)
				)
				(justify left bottom)
				(hide yes)
			)
		)
		(property "Footprint" "antmicro-footprints:C_0402_1005Metric"
			(at 173.99 44.45 0)
			(effects
				(font
					(size 1.27 1.27)
					(thickness 0.15)
				)
				(justify left bottom)
				(hide yes)
			)
		)
		(property "Datasheet" "https://www.murata.com/products/productdetail?partno=GRM155R61H104KE14%23"
			(at 176.53 44.45 0)
			(effects
				(font
					(size 1.27 1.27)
					(thickness 0.15)
				)
				(justify left bottom)
				(hide yes)
			)
		)
		(property "Description" ""
			(at 161.29 64.77 0)
			(effects
				(font
					(size 1.27 1.27)
				)
			)
		)
		(property "Manufacturer" "Murata"
			(at 181.61 44.45 0)
			(effects
				(font
					(size 1.27 1.27)
					(thickness 0.15)
				)
				(justify left bottom)
				(hide yes)
			)
		)
		(property "MPN" "GRM155R61H104KE14D"
			(at 179.07 44.45 0)
			(effects
				(font
					(size 1.27 1.27)
					(thickness 0.15)
				)
				(justify left bottom)
				(hide yes)
			)
		)
		(property "Val" "100n"
			(at 162.56 64.77 90)
			(effects
				(font
					(size 1.27 1.27)
					(thickness 0.15)
				)
				(justify right)
			)
		)
		(property "License" "Apache-2.0"
			(at 184.15 44.45 0)
			(effects
				(font
					(size 1.27 1.27)
					(thickness 0.15)
				)
				(justify left bottom)
				(hide yes)
			)
		)
		(property "Author" "Antmicro"
			(at 186.69 44.45 0)
			(effects
				(font
					(size 1.27 1.27)
					(thickness 0.15)
				)
				(justify left bottom)
				(hide yes)
			)
		)
		(property "Voltage" "50V"
			(at 189.23 44.45 0)
			(effects
				(font
					(size 1.27 1.27)
				)
				(justify left bottom)
				(hide yes)
			)
		)
		(property "Dielectric" "X5R"
			(at 191.77 44.45 0)
			(effects
				(font
					(size 1.27 1.27)
				)
				(justify left bottom)
				(hide yes)
			)
		)
		(pin "1"
		)
		(pin "2"
		)
		(instances
			(project "k410t-devboard"
				(path ""
					(reference "C37")
					(unit 1)
				)
			)
		)
	)
	(symbol
		(lib_id "antmicropower:+3.3V")
		(at 106.68 55.88 0)
		(unit 1)
		(exclude_from_sim no)
		(in_bom yes)
		(on_board yes)
		(dnp no)
		(fields_autoplaced yes)
		(property "Reference" "#PWR011"
			(at 106.68 59.69 0)
			(effects
				(font
					(size 1.27 1.27)
				)
				(hide yes)
			)
		)
		(property "Value" "+3V3"
			(at 106.68 52.324 0)
			(effects
				(font
					(size 1.27 1.27)
				)
			)
		)
		(property "Footprint" ""
			(at 106.68 55.88 0)
			(effects
				(font
					(size 1.27 1.27)
				)
				(hide yes)
			)
		)
		(property "Datasheet" ""
			(at 106.68 55.88 0)
			(effects
				(font
					(size 1.27 1.27)
				)
				(hide yes)
			)
		)
		(property "Description" ""
			(at 106.68 55.88 0)
			(effects
				(font
					(size 1.27 1.27)
				)
			)
		)
		(pin "1"
		)
		(instances
			(project "k410t-devboard"
				(path ""
					(reference "#PWR011")
					(unit 1)
				)
			)
		)
	)
	(symbol
		(lib_id "antmicropower:VCC_USR_A")
		(at 320.04 54.61 0)
		(mirror y)
		(unit 1)
		(exclude_from_sim no)
		(in_bom yes)
		(on_board yes)
		(dnp no)
		(fields_autoplaced yes)
		(property "Reference" "#PWR012"
			(at 320.04 58.42 0)
			(effects
				(font
					(size 1.27 1.27)
				)
				(hide yes)
			)
		)
		(property "Value" "VCC_USR_A"
			(at 320.04 50.8 0)
			(effects
				(font
					(size 1.27 1.27)
				)
			)
		)
		(property "Footprint" ""
			(at 320.04 54.61 0)
			(effects
				(font
					(size 1.27 1.27)
				)
				(hide yes)
			)
		)
		(property "Datasheet" ""
			(at 320.04 54.61 0)
			(effects
				(font
					(size 1.27 1.27)
				)
				(hide yes)
			)
		)
		(property "Description" ""
			(at 320.04 54.61 0)
			(effects
				(font
					(size 1.27 1.27)
				)
			)
		)
		(pin "1"
		)
		(instances
			(project "k410t-devboard"
				(path ""
					(reference "#PWR012")
					(unit 1)
				)
			)
		)
	)
	(symbol
		(lib_id "antmicroResistors0402:R_1k_0402")
		(at 110.49 210.82 90)
		(unit 1)
		(exclude_from_sim no)
		(in_bom yes)
		(on_board yes)
		(dnp no)
		(fields_autoplaced yes)
		(property "Reference" "R338"
			(at 108.585 207.0099 90)
			(effects
				(font
					(size 1.27 1.27)
				)
				(justify left)
			)
		)
		(property "Value" "R_1k_0402"
			(at 123.19 190.5 0)
			(effects
				(font
					(size 1.27 1.27)
					(thickness 0.15)
				)
				(justify left bottom)
				(hide yes)
			)
		)
		(property "Footprint" "antmicro-footprints:R_0402_1005Metric"
			(at 125.73 190.5 0)
			(effects
				(font
					(size 1.27 1.27)
					(thickness 0.15)
				)
				(justify left bottom)
				(hide yes)
			)
		)
		(property "Datasheet" "https://www.bourns.com/docs/product-datasheets/cr.pdf"
			(at 128.27 190.5 0)
			(effects
				(font
					(size 1.27 1.27)
					(thickness 0.15)
				)
				(justify left bottom)
				(hide yes)
			)
		)
		(property "Description" ""
			(at 110.49 210.82 0)
			(effects
				(font
					(size 1.27 1.27)
				)
			)
		)
		(property "Manufacturer" "Bourns"
			(at 133.35 190.5 0)
			(effects
				(font
					(size 1.27 1.27)
					(thickness 0.15)
				)
				(justify left bottom)
				(hide yes)
			)
		)
		(property "MPN" "CR0402-FX-1001GLF"
			(at 130.81 190.5 0)
			(effects
				(font
					(size 1.27 1.27)
					(thickness 0.15)
				)
				(justify left bottom)
				(hide yes)
			)
		)
		(property "Val" "1k"
			(at 108.585 209.5499 90)
			(effects
				(font
					(size 1.27 1.27)
					(thickness 0.15)
				)
				(justify left)
			)
		)
		(property "License" "Apache-2.0"
			(at 135.89 190.5 0)
			(effects
				(font
					(size 1.27 1.27)
					(thickness 0.15)
				)
				(justify left bottom)
				(hide yes)
			)
		)
		(property "Author" "Antmicro"
			(at 138.43 190.5 0)
			(effects
				(font
					(size 1.27 1.27)
					(thickness 0.15)
				)
				(justify left bottom)
				(hide yes)
			)
		)
		(property "Tolerance" "1%"
			(at 120.65 190.5 0)
			(effects
				(font
					(size 1.27 1.27)
				)
				(justify left bottom)
				(hide yes)
			)
		)
		(pin "1"
		)
		(pin "2"
		)
		(instances
			(project "k410t-devboard"
				(path ""
					(reference "R338")
					(unit 1)
				)
			)
		)
	)
	(symbol
		(lib_id "antmicroCapacitors0402:C_100n_0402")
		(at 168.91 64.77 90)
		(unit 1)
		(exclude_from_sim no)
		(in_bom yes)
		(on_board yes)
		(dnp no)
		(property "Reference" "C42"
			(at 170.18 59.69 90)
			(effects
				(font
					(size 1.27 1.27)
				)
				(justify right)
			)
		)
		(property "Value" "C_100n_0402"
			(at 179.07 44.45 0)
			(effects
				(font
					(size 1.27 1.27)
					(thickness 0.15)
				)
				(justify left bottom)
				(hide yes)
			)
		)
		(property "Footprint" "antmicro-footprints:C_0402_1005Metric"
			(at 181.61 44.45 0)
			(effects
				(font
					(size 1.27 1.27)
					(thickness 0.15)
				)
				(justify left bottom)
				(hide yes)
			)
		)
		(property "Datasheet" "https://www.murata.com/products/productdetail?partno=GRM155R61H104KE14%23"
			(at 184.15 44.45 0)
			(effects
				(font
					(size 1.27 1.27)
					(thickness 0.15)
				)
				(justify left bottom)
				(hide yes)
			)
		)
		(property "Description" ""
			(at 168.91 64.77 0)
			(effects
				(font
					(size 1.27 1.27)
				)
			)
		)
		(property "Manufacturer" "Murata"
			(at 189.23 44.45 0)
			(effects
				(font
					(size 1.27 1.27)
					(thickness 0.15)
				)
				(justify left bottom)
				(hide yes)
			)
		)
		(property "MPN" "GRM155R61H104KE14D"
			(at 186.69 44.45 0)
			(effects
				(font
					(size 1.27 1.27)
					(thickness 0.15)
				)
				(justify left bottom)
				(hide yes)
			)
		)
		(property "Val" "100n"
			(at 170.18 64.77 90)
			(effects
				(font
					(size 1.27 1.27)
					(thickness 0.15)
				)
				(justify right)
			)
		)
		(property "License" "Apache-2.0"
			(at 191.77 44.45 0)
			(effects
				(font
					(size 1.27 1.27)
					(thickness 0.15)
				)
				(justify left bottom)
				(hide yes)
			)
		)
		(property "Author" "Antmicro"
			(at 194.31 44.45 0)
			(effects
				(font
					(size 1.27 1.27)
					(thickness 0.15)
				)
				(justify left bottom)
				(hide yes)
			)
		)
		(property "Voltage" "50V"
			(at 196.85 44.45 0)
			(effects
				(font
					(size 1.27 1.27)
				)
				(justify left bottom)
				(hide yes)
			)
		)
		(property "Dielectric" "X5R"
			(at 199.39 44.45 0)
			(effects
				(font
					(size 1.27 1.27)
				)
				(justify left bottom)
				(hide yes)
			)
		)
		(pin "1"
		)
		(pin "2"
		)
		(instances
			(project "k410t-devboard"
				(path ""
					(reference "C42")
					(unit 1)
				)
			)
		)
	)
	(symbol
		(lib_id "antmicroCapacitors0402:C_100n_0402")
		(at 153.67 64.77 90)
		(unit 1)
		(exclude_from_sim no)
		(in_bom yes)
		(on_board yes)
		(dnp no)
		(property "Reference" "C31"
			(at 154.94 59.69 90)
			(effects
				(font
					(size 1.27 1.27)
				)
				(justify right)
			)
		)
		(property "Value" "C_100n_0402"
			(at 163.83 44.45 0)
			(effects
				(font
					(size 1.27 1.27)
					(thickness 0.15)
				)
				(justify left bottom)
				(hide yes)
			)
		)
		(property "Footprint" "antmicro-footprints:C_0402_1005Metric"
			(at 166.37 44.45 0)
			(effects
				(font
					(size 1.27 1.27)
					(thickness 0.15)
				)
				(justify left bottom)
				(hide yes)
			)
		)
		(property "Datasheet" "https://www.murata.com/products/productdetail?partno=GRM155R61H104KE14%23"
			(at 168.91 44.45 0)
			(effects
				(font
					(size 1.27 1.27)
					(thickness 0.15)
				)
				(justify left bottom)
				(hide yes)
			)
		)
		(property "Description" ""
			(at 153.67 64.77 0)
			(effects
				(font
					(size 1.27 1.27)
				)
			)
		)
		(property "Manufacturer" "Murata"
			(at 173.99 44.45 0)
			(effects
				(font
					(size 1.27 1.27)
					(thickness 0.15)
				)
				(justify left bottom)
				(hide yes)
			)
		)
		(property "MPN" "GRM155R61H104KE14D"
			(at 171.45 44.45 0)
			(effects
				(font
					(size 1.27 1.27)
					(thickness 0.15)
				)
				(justify left bottom)
				(hide yes)
			)
		)
		(property "Val" "100n"
			(at 154.94 64.77 90)
			(effects
				(font
					(size 1.27 1.27)
					(thickness 0.15)
				)
				(justify right)
			)
		)
		(property "License" "Apache-2.0"
			(at 176.53 44.45 0)
			(effects
				(font
					(size 1.27 1.27)
					(thickness 0.15)
				)
				(justify left bottom)
				(hide yes)
			)
		)
		(property "Author" "Antmicro"
			(at 179.07 44.45 0)
			(effects
				(font
					(size 1.27 1.27)
					(thickness 0.15)
				)
				(justify left bottom)
				(hide yes)
			)
		)
		(property "Voltage" "50V"
			(at 181.61 44.45 0)
			(effects
				(font
					(size 1.27 1.27)
				)
				(justify left bottom)
				(hide yes)
			)
		)
		(property "Dielectric" "X5R"
			(at 184.15 44.45 0)
			(effects
				(font
					(size 1.27 1.27)
				)
				(justify left bottom)
				(hide yes)
			)
		)
		(pin "1"
		)
		(pin "2"
		)
		(instances
			(project "k410t-devboard"
				(path ""
					(reference "C31")
					(unit 1)
				)
			)
		)
	)
	(symbol
		(lib_id "antmicroCapacitors0402:C_100n_0402")
		(at 138.43 64.77 90)
		(unit 1)
		(exclude_from_sim no)
		(in_bom yes)
		(on_board yes)
		(dnp no)
		(property "Reference" "C19"
			(at 139.7 59.69 90)
			(effects
				(font
					(size 1.27 1.27)
				)
				(justify right)
			)
		)
		(property "Value" "C_100n_0402"
			(at 148.59 44.45 0)
			(effects
				(font
					(size 1.27 1.27)
					(thickness 0.15)
				)
				(justify left bottom)
				(hide yes)
			)
		)
		(property "Footprint" "antmicro-footprints:C_0402_1005Metric"
			(at 151.13 44.45 0)
			(effects
				(font
					(size 1.27 1.27)
					(thickness 0.15)
				)
				(justify left bottom)
				(hide yes)
			)
		)
		(property "Datasheet" "https://www.murata.com/products/productdetail?partno=GRM155R61H104KE14%23"
			(at 153.67 44.45 0)
			(effects
				(font
					(size 1.27 1.27)
					(thickness 0.15)
				)
				(justify left bottom)
				(hide yes)
			)
		)
		(property "Description" ""
			(at 138.43 64.77 0)
			(effects
				(font
					(size 1.27 1.27)
				)
			)
		)
		(property "Manufacturer" "Murata"
			(at 158.75 44.45 0)
			(effects
				(font
					(size 1.27 1.27)
					(thickness 0.15)
				)
				(justify left bottom)
				(hide yes)
			)
		)
		(property "MPN" "GRM155R61H104KE14D"
			(at 156.21 44.45 0)
			(effects
				(font
					(size 1.27 1.27)
					(thickness 0.15)
				)
				(justify left bottom)
				(hide yes)
			)
		)
		(property "Val" "100n"
			(at 139.7 64.77 90)
			(effects
				(font
					(size 1.27 1.27)
					(thickness 0.15)
				)
				(justify right)
			)
		)
		(property "License" "Apache-2.0"
			(at 161.29 44.45 0)
			(effects
				(font
					(size 1.27 1.27)
					(thickness 0.15)
				)
				(justify left bottom)
				(hide yes)
			)
		)
		(property "Author" "Antmicro"
			(at 163.83 44.45 0)
			(effects
				(font
					(size 1.27 1.27)
					(thickness 0.15)
				)
				(justify left bottom)
				(hide yes)
			)
		)
		(property "Voltage" "50V"
			(at 166.37 44.45 0)
			(effects
				(font
					(size 1.27 1.27)
				)
				(justify left bottom)
				(hide yes)
			)
		)
		(property "Dielectric" "X5R"
			(at 168.91 44.45 0)
			(effects
				(font
					(size 1.27 1.27)
				)
				(justify left bottom)
				(hide yes)
			)
		)
		(pin "1"
		)
		(pin "2"
		)
		(instances
			(project "k410t-devboard"
				(path ""
					(reference "C19")
					(unit 1)
				)
			)
		)
	)
	(symbol
		(lib_id "antmicroFPGAChips:XC7K410T-2FFG900I")
		(at 179.07 88.9 0)
		(unit 2)
		(exclude_from_sim no)
		(in_bom yes)
		(on_board yes)
		(dnp no)
		(fields_autoplaced yes)
		(property "Reference" "U1"
			(at 213.995 78.74 0)
			(effects
				(font
					(size 1.27 1.27)
					(thickness 0.15)
				)
			)
		)
		(property "Value" "XC7K410T-2FFG900I"
			(at 213.995 81.28 0)
			(effects
				(font
					(size 1.27 1.27)
					(thickness 0.15)
				)
			)
		)
		(property "Footprint" "antmicro-footprints:BGA-900_31x31mm_Layout30x30_P1x1mm_FFG900"
			(at 179.07 62.23 0)
			(effects
				(font
					(size 1.27 1.27)
					(thickness 0.15)
				)
				(justify left bottom)
				(hide yes)
			)
		)
		(property "Datasheet" "https://eu.mouser.com/datasheet/2/903/ds180_7Series_Overview-1591537.pdf"
			(at 179.07 64.77 0)
			(effects
				(font
					(size 1.27 1.27)
					(thickness 0.15)
				)
				(justify left bottom)
				(hide yes)
			)
		)
		(property "Description" ""
			(at 179.07 88.9 0)
			(effects
				(font
					(size 1.27 1.27)
				)
			)
		)
		(property "Manufacturer" "AMD-Xilinx"
			(at 179.07 67.31 0)
			(effects
				(font
					(size 1.27 1.27)
					(thickness 0.15)
				)
				(justify left bottom)
				(hide yes)
			)
		)
		(property "MPN" "XC7K410T-2FFG900I"
			(at 179.07 69.85 0)
			(effects
				(font
					(size 1.27 1.27)
					(thickness 0.15)
				)
				(justify left bottom)
				(hide yes)
			)
		)
		(property "Author" "Antmicro"
			(at 179.07 72.39 0)
			(effects
				(font
					(size 1.27 1.27)
					(thickness 0.15)
				)
				(justify left bottom)
				(hide yes)
			)
		)
		(property "License" "Apache-2.0"
			(at 179.07 74.93 0)
			(effects
				(font
					(size 1.27 1.27)
					(thickness 0.15)
				)
				(justify left bottom)
				(hide yes)
			)
		)
		(pin "P24"
		)
		(pin "P26"
		)
		(pin "P27"
		)
		(pin "P28"
		)
		(pin "P29"
		)
		(pin "R19"
		)
		(pin "R20"
		)
		(pin "R21"
		)
		(pin "R23"
		)
		(pin "R24"
		)
		(pin "R25"
		)
		(pin "R26"
		)
		(pin "R28"
		)
		(pin "R29"
		)
		(pin "R30"
		)
		(pin "T20"
		)
		(pin "T21"
		)
		(pin "T22"
		)
		(pin "T23"
		)
		(pin "T25"
		)
		(pin "T26"
		)
		(pin "T27"
		)
		(pin "T28"
		)
		(pin "T30"
		)
		(pin "U19"
		)
		(pin "U20"
		)
		(pin "U22"
		)
		(pin "U23"
		)
		(pin "U24"
		)
		(pin "U25"
		)
		(pin "U27"
		)
		(pin "U28"
		)
		(pin "U29"
		)
		(pin "U30"
		)
		(pin "V19"
		)
		(pin "V20"
		)
		(pin "V21"
		)
		(pin "V22"
		)
		(pin "V24"
		)
		(pin "V25"
		)
		(pin "V26"
		)
		(pin "V27"
		)
		(pin "V29"
		)
		(pin "V30"
		)
		(pin "W19"
		)
		(pin "W21"
		)
		(pin "W22"
		)
		(pin "W23"
		)
		(pin "W24"
		)
		(pin "W26"
		)
		(pin "AA20"
		)
		(pin "AA21"
		)
		(pin "AA22"
		)
		(pin "AA23"
		)
		(pin "AB20"
		)
		(pin "AB22"
		)
		(pin "AB23"
		)
		(pin "AB24"
		)
		(pin "AC20"
		)
		(pin "AC21"
		)
		(pin "AC22"
		)
		(pin "AC24"
		)
		(pin "AC25"
		)
		(pin "AD21"
		)
		(pin "AD22"
		)
		(pin "AD23"
		)
		(pin "AD24"
		)
		(pin "AE20"
		)
		(pin "AE21"
		)
		(pin "AE23"
		)
		(pin "AE24"
		)
		(pin "AE25"
		)
		(pin "AF20"
		)
		(pin "AF21"
		)
		(pin "AF22"
		)
		(pin "AF23"
		)
		(pin "AF25"
		)
		(pin "AG20"
		)
		(pin "AG22"
		)
		(pin "AG23"
		)
		(pin "AG24"
		)
		(pin "AG25"
		)
		(pin "AH20"
		)
		(pin "AH21"
		)
		(pin "AH22"
		)
		(pin "AH24"
		)
		(pin "AH25"
		)
		(pin "AJ21"
		)
		(pin "AJ22"
		)
		(pin "AJ23"
		)
		(pin "AJ24"
		)
		(pin "AK20"
		)
		(pin "AK21"
		)
		(pin "AK23"
		)
		(pin "AK24"
		)
		(pin "AK25"
		)
		(pin "Y20"
		)
		(pin "Y21"
		)
		(pin "Y23"
		)
		(pin "Y24"
		)
		(pin "A23"
		)
		(pin "A25"
		)
		(pin "A26"
		)
		(pin "A27"
		)
		(pin "A28"
		)
		(pin "A30"
		)
		(pin "B23"
		)
		(pin "B24"
		)
		(pin "B25"
		)
		(pin "B27"
		)
		(pin "B28"
		)
		(pin "B29"
		)
		(pin "B30"
		)
		(pin "C24"
		)
		(pin "C25"
		)
		(pin "C26"
		)
		(pin "C27"
		)
		(pin "C29"
		)
		(pin "C30"
		)
		(pin "D23"
		)
		(pin "D24"
		)
		(pin "D26"
		)
		(pin "D27"
		)
		(pin "D28"
		)
		(pin "D29"
		)
		(pin "E23"
		)
		(pin "E24"
		)
		(pin "E25"
		)
		(pin "E26"
		)
		(pin "B2"
		)
		(pin "B5"
		)
		(pin "B6"
		)
		(pin "C3"
		)
		(pin "C4"
		)
		(pin "E28"
		)
		(pin "E29"
		)
		(pin "E30"
		)
		(pin "F23"
		)
		(pin "F25"
		)
		(pin "F26"
		)
		(pin "F27"
		)
		(pin "F28"
		)
		(pin "F30"
		)
		(pin "G23"
		)
		(pin "G24"
		)
		(pin "G25"
		)
		(pin "G27"
		)
		(pin "G28"
		)
		(pin "G29"
		)
		(pin "G30"
		)
		(pin "H24"
		)
		(pin "H25"
		)
		(pin "H26"
		)
		(pin "H27"
		)
		(pin "H30"
		)
		(pin "A11"
		)
		(pin "A12"
		)
		(pin "A13"
		)
		(pin "A15"
		)
		(pin "B12"
		)
		(pin "B13"
		)
		(pin "B14"
		)
		(pin "B15"
		)
		(pin "C11"
		)
		(pin "C12"
		)
		(pin "C14"
		)
		(pin "C15"
		)
		(pin "D11"
		)
		(pin "D12"
		)
		(pin "D13"
		)
		(pin "D14"
		)
		(pin "E11"
		)
		(pin "E13"
		)
		(pin "E14"
		)
		(pin "E15"
		)
		(pin "E16"
		)
		(pin "F11"
		)
		(pin "F12"
		)
		(pin "F13"
		)
		(pin "F15"
		)
		(pin "F16"
		)
		(pin "G12"
		)
		(pin "G13"
		)
		(pin "G14"
		)
		(pin "G15"
		)
		(pin "H11"
		)
		(pin "H12"
		)
		(pin "H14"
		)
		(pin "H15"
		)
		(pin "H16"
		)
		(pin "J11"
		)
		(pin "J12"
		)
		(pin "J13"
		)
		(pin "J14"
		)
		(pin "J16"
		)
		(pin "K11"
		)
		(pin "K13"
		)
		(pin "K14"
		)
		(pin "K15"
		)
		(pin "K16"
		)
		(pin "L11"
		)
		(pin "L12"
		)
		(pin "L13"
		)
		(pin "L15"
		)
		(pin "L16"
		)
		(pin "AA10"
		)
		(pin "AA11"
		)
		(pin "AA12"
		)
		(pin "AA13"
		)
		(pin "AA8"
		)
		(pin "AB10"
		)
		(pin "AB12"
		)
		(pin "AB13"
		)
		(pin "AB8"
		)
		(pin "AB9"
		)
		(pin "AC10"
		)
		(pin "AC11"
		)
		(pin "AC12"
		)
		(pin "AC9"
		)
		(pin "AD11"
		)
		(pin "AD12"
		)
		(pin "AD13"
		)
		(pin "AD8"
		)
		(pin "AD9"
		)
		(pin "AE10"
		)
		(pin "AE11"
		)
		(pin "AE13"
		)
		(pin "AE8"
		)
		(pin "AE9"
		)
		(pin "AF10"
		)
		(pin "AF11"
		)
		(pin "AF12"
		)
		(pin "AF13"
		)
		(pin "AG10"
		)
		(pin "AG12"
		)
		(pin "AG13"
		)
		(pin "AG9"
		)
		(pin "AH10"
		)
		(pin "AH11"
		)
		(pin "AH12"
		)
		(pin "AH14"
		)
		(pin "AH9"
		)
		(pin "AJ11"
		)
		(pin "AJ12"
		)
		(pin "AJ13"
		)
		(pin "AJ14"
		)
		(pin "AJ9"
		)
		(pin "AK10"
		)
		(pin "AK11"
		)
		(pin "AK13"
		)
		(pin "AK14"
		)
		(pin "AK9"
		)
		(pin "Y10"
		)
		(pin "Y11"
		)
		(pin "Y13"
		)
		(pin "A3"
		)
		(pin "A4"
		)
		(pin "A7"
		)
		(pin "A8"
		)
		(pin "AA3"
		)
		(pin "AA4"
		)
		(pin "B1"
		)
		(pin "G16"
		)
		(pin "G2"
		)
		(pin "G26"
		)
		(pin "G6"
		)
		(pin "G9"
		)
		(pin "H13"
		)
		(pin "H23"
		)
		(pin "H4"
		)
		(pin "H8"
		)
		(pin "H9"
		)
		(pin "J1"
		)
		(pin "J10"
		)
		(pin "C7"
		)
		(pin "C8"
		)
		(pin "D1"
		)
		(pin "D2"
		)
		(pin "D5"
		)
		(pin "D6"
		)
		(pin "E3"
		)
		(pin "E4"
		)
		(pin "E7"
		)
		(pin "E8"
		)
		(pin "F1"
		)
		(pin "F2"
		)
		(pin "F5"
		)
		(pin "F6"
		)
		(pin "G3"
		)
		(pin "G4"
		)
		(pin "G7"
		)
		(pin "G8"
		)
		(pin "H1"
		)
		(pin "H2"
		)
		(pin "H5"
		)
		(pin "H6"
		)
		(pin "J3"
		)
		(pin "J4"
		)
		(pin "J7"
		)
		(pin "J8"
		)
		(pin "K1"
		)
		(pin "K2"
		)
		(pin "K5"
		)
		(pin "K6"
		)
		(pin "L3"
		)
		(pin "L4"
		)
		(pin "L7"
		)
		(pin "L8"
		)
		(pin "M1"
		)
		(pin "M2"
		)
		(pin "M5"
		)
		(pin "M6"
		)
		(pin "N3"
		)
		(pin "N4"
		)
		(pin "N7"
		)
		(pin "N8"
		)
		(pin "P1"
		)
		(pin "P2"
		)
		(pin "P5"
		)
		(pin "P6"
		)
		(pin "R3"
		)
		(pin "R4"
		)
		(pin "R7"
		)
		(pin "R8"
		)
		(pin "T1"
		)
		(pin "T2"
		)
		(pin "T5"
		)
		(pin "T6"
		)
		(pin "U3"
		)
		(pin "U4"
		)
		(pin "U7"
		)
		(pin "U8"
		)
		(pin "V1"
		)
		(pin "V2"
		)
		(pin "V5"
		)
		(pin "V6"
		)
		(pin "W3"
		)
		(pin "W4"
		)
		(pin "Y1"
		)
		(pin "Y2"
		)
		(pin "Y5"
		)
		(pin "Y6"
		)
		(pin "B3"
		)
		(pin "B7"
		)
		(pin "C5"
		)
		(pin "D3"
		)
		(pin "D7"
		)
		(pin "E5"
		)
		(pin "F3"
		)
		(pin "F7"
		)
		(pin "G5"
		)
		(pin "H3"
		)
		(pin "H7"
		)
		(pin "J5"
		)
		(pin "K3"
		)
		(pin "K7"
		)
		(pin "L5"
		)
		(pin "M3"
		)
		(pin "M7"
		)
		(pin "N5"
		)
		(pin "P3"
		)
		(pin "P7"
		)
		(pin "R5"
		)
		(pin "T3"
		)
		(pin "T7"
		)
		(pin "U5"
		)
		(pin "V3"
		)
		(pin "V7"
		)
		(pin "W5"
		)
		(pin "W7"
		)
		(pin "W8"
		)
		(pin "A10"
		)
		(pin "AB1"
		)
		(pin "AB2"
		)
		(pin "AB5"
		)
		(pin "B10"
		)
		(pin "E10"
		)
		(pin "F10"
		)
		(pin "G10"
		)
		(pin "H10"
		)
		(pin "K10"
		)
		(pin "L10"
		)
		(pin "M10"
		)
		(pin "R14"
		)
		(pin "R15"
		)
		(pin "T14"
		)
		(pin "T15"
		)
		(pin "U14"
		)
		(pin "U15"
		)
		(pin "A19"
		)
		(pin "A29"
		)
		(pin "AA19"
		)
		(pin "AA29"
		)
		(pin "AA9"
		)
		(pin "AB16"
		)
		(pin "AB26"
		)
		(pin "AB6"
		)
		(pin "AC13"
		)
		(pin "AC23"
		)
		(pin "AC3"
		)
		(pin "AD10"
		)
		(pin "AD20"
		)
		(pin "AD30"
		)
		(pin "AE17"
		)
		(pin "AE27"
		)
		(pin "AE7"
		)
		(pin "AF14"
		)
		(pin "AF24"
		)
		(pin "AF4"
		)
		(pin "AG1"
		)
		(pin "AG11"
		)
		(pin "AG21"
		)
		(pin "AH18"
		)
		(pin "AH28"
		)
		(pin "AH8"
		)
		(pin "AJ15"
		)
		(pin "AJ25"
		)
		(pin "AJ5"
		)
		(pin "AK12"
		)
		(pin "AK2"
		)
		(pin "AK22"
		)
		(pin "B16"
		)
		(pin "B26"
		)
		(pin "C13"
		)
		(pin "C23"
		)
		(pin "D10"
		)
		(pin "D20"
		)
		(pin "D30"
		)
		(pin "E17"
		)
		(pin "E27"
		)
		(pin "F14"
		)
		(pin "F24"
		)
		(pin "G11"
		)
		(pin "G21"
		)
		(pin "H18"
		)
		(pin "H28"
		)
		(pin "J15"
		)
		(pin "J25"
		)
		(pin "K12"
		)
		(pin "K22"
		)
		(pin "L19"
		)
		(pin "L29"
		)
		(pin "M26"
		)
		(pin "N23"
		)
		(pin "P20"
		)
		(pin "P30"
		)
		(pin "R27"
		)
		(pin "T24"
		)
		(pin "T9"
		)
		(pin "U21"
		)
		(pin "V28"
		)
		(pin "W25"
		)
		(pin "Y12"
		)
		(pin "Y22"
		)
		(pin "A1"
		)
		(pin "A14"
		)
		(pin "A2"
		)
		(pin "A24"
		)
		(pin "A5"
		)
		(pin "A6"
		)
		(pin "A9"
		)
		(pin "AA1"
		)
		(pin "AA14"
		)
		(pin "AA2"
		)
		(pin "AA24"
		)
		(pin "AA5"
		)
		(pin "AA6"
		)
		(pin "AA7"
		)
		(pin "AB11"
		)
		(pin "AB21"
		)
		(pin "AB3"
		)
		(pin "AB4"
		)
		(pin "AC18"
		)
		(pin "AC28"
		)
		(pin "AC8"
		)
		(pin "AD15"
		)
		(pin "AD25"
		)
		(pin "AD5"
		)
		(pin "AE12"
		)
		(pin "AE2"
		)
		(pin "AE22"
		)
		(pin "AF19"
		)
		(pin "AF29"
		)
		(pin "AF9"
		)
		(pin "AG16"
		)
		(pin "AG26"
		)
		(pin "AG6"
		)
		(pin "AH13"
		)
		(pin "AH23"
		)
		(pin "AH3"
		)
		(pin "AJ10"
		)
		(pin "AJ20"
		)
		(pin "AJ30"
		)
		(pin "AK17"
		)
		(pin "AK27"
		)
		(pin "AK7"
		)
		(pin "B11"
		)
		(pin "B21"
		)
		(pin "B4"
		)
		(pin "B8"
		)
		(pin "B9"
		)
		(pin "C1"
		)
		(pin "C10"
		)
		(pin "C18"
		)
		(pin "C2"
		)
		(pin "C28"
		)
		(pin "C6"
		)
		(pin "C9"
		)
		(pin "D15"
		)
		(pin "D25"
		)
		(pin "D4"
		)
		(pin "D8"
		)
		(pin "D9"
		)
		(pin "E1"
		)
		(pin "E12"
		)
		(pin "E2"
		)
		(pin "E22"
		)
		(pin "E6"
		)
		(pin "E9"
		)
		(pin "F19"
		)
		(pin "F29"
		)
		(pin "F4"
		)
		(pin "F8"
		)
		(pin "F9"
		)
		(pin "G1"
		)
		(pin "J2"
		)
		(pin "J20"
		)
		(pin "J30"
		)
		(pin "J6"
		)
		(pin "J9"
		)
		(pin "K17"
		)
		(pin "K27"
		)
		(pin "K4"
		)
		(pin "K8"
		)
		(pin "K9"
		)
		(pin "L1"
		)
		(pin "L14"
		)
		(pin "L2"
		)
		(pin "L24"
		)
		(pin "L6"
		)
		(pin "L9"
		)
		(pin "M11"
		)
		(pin "M12"
		)
		(pin "M13"
		)
		(pin "M14"
		)
		(pin "M15"
		)
		(pin "M16"
		)
		(pin "M17"
		)
		(pin "M18"
		)
		(pin "M21"
		)
		(pin "M4"
		)
		(pin "M8"
		)
		(pin "M9"
		)
		(pin "N1"
		)
		(pin "N10"
		)
		(pin "N11"
		)
		(pin "N12"
		)
		(pin "N13"
		)
		(pin "N14"
		)
		(pin "N15"
		)
		(pin "N16"
		)
		(pin "N17"
		)
		(pin "N18"
		)
		(pin "N2"
		)
		(pin "N28"
		)
		(pin "N6"
		)
		(pin "N9"
		)
		(pin "P10"
		)
		(pin "P11"
		)
		(pin "P12"
		)
		(pin "P13"
		)
		(pin "P14"
		)
		(pin "P15"
		)
		(pin "P16"
		)
		(pin "P17"
		)
		(pin "P18"
		)
		(pin "P25"
		)
		(pin "P4"
		)
		(pin "P8"
		)
		(pin "P9"
		)
		(pin "R1"
		)
		(pin "R10"
		)
		(pin "R11"
		)
		(pin "R12"
		)
		(pin "R13"
		)
		(pin "R16"
		)
		(pin "R17"
		)
		(pin "R18"
		)
		(pin "R2"
		)
		(pin "R22"
		)
		(pin "R6"
		)
		(pin "R9"
		)
		(pin "T10"
		)
		(pin "T11"
		)
		(pin "T12"
		)
		(pin "T13"
		)
		(pin "T16"
		)
		(pin "T17"
		)
		(pin "T18"
		)
		(pin "T19"
		)
		(pin "T29"
		)
		(pin "T4"
		)
		(pin "T8"
		)
		(pin "U1"
		)
		(pin "U10"
		)
		(pin "U11"
		)
		(pin "U12"
		)
		(pin "U13"
		)
		(pin "U16"
		)
		(pin "U17"
		)
		(pin "U18"
		)
		(pin "U2"
		)
		(pin "U26"
		)
		(pin "U6"
		)
		(pin "U9"
		)
		(pin "V10"
		)
		(pin "V11"
		)
		(pin "V12"
		)
		(pin "V13"
		)
		(pin "V14"
		)
		(pin "V15"
		)
		(pin "V16"
		)
		(pin "V17"
		)
		(pin "V18"
		)
		(pin "V23"
		)
		(pin "V4"
		)
		(pin "V8"
		)
		(pin "V9"
		)
		(pin "W1"
		)
		(pin "W10"
		)
		(pin "W11"
		)
		(pin "W12"
		)
		(pin "W13"
		)
		(pin "W14"
		)
		(pin "W15"
		)
		(pin "W16"
		)
		(pin "W17"
		)
		(pin "W18"
		)
		(pin "W2"
		)
		(pin "W20"
		)
		(pin "W30"
		)
		(pin "W6"
		)
		(pin "W9"
		)
		(pin "Y17"
		)
		(pin "Y27"
		)
		(pin "Y3"
		)
		(pin "Y4"
		)
		(pin "Y7"
		)
		(pin "Y8"
		)
		(pin "Y9"
		)
		(pin "AA25"
		)
		(pin "AA26"
		)
		(pin "AA27"
		)
		(pin "AA28"
		)
		(pin "AA30"
		)
		(pin "AB25"
		)
		(pin "AB27"
		)
		(pin "AB28"
		)
		(pin "AB29"
		)
		(pin "AB30"
		)
		(pin "AC26"
		)
		(pin "AC27"
		)
		(pin "AC29"
		)
		(pin "AC30"
		)
		(pin "AD26"
		)
		(pin "AD27"
		)
		(pin "AD28"
		)
		(pin "AD29"
		)
		(pin "AE26"
		)
		(pin "AE28"
		)
		(pin "AE29"
		)
		(pin "AE30"
		)
		(pin "AF26"
		)
		(pin "AF27"
		)
		(pin "AF28"
		)
		(pin "AF30"
		)
		(pin "AG27"
		)
		(pin "AG28"
		)
		(pin "AG29"
		)
		(pin "AG30"
		)
		(pin "AH26"
		)
		(pin "AH27"
		)
		(pin "AH29"
		)
		(pin "AH30"
		)
		(pin "AJ26"
		)
		(pin "AJ27"
		)
		(pin "AJ28"
		)
		(pin "AJ29"
		)
		(pin "AK26"
		)
		(pin "AK28"
		)
		(pin "AK29"
		)
		(pin "AK30"
		)
		(pin "W27"
		)
		(pin "W28"
		)
		(pin "W29"
		)
		(pin "Y25"
		)
		(pin "Y26"
		)
		(pin "Y28"
		)
		(pin "Y29"
		)
		(pin "Y30"
		)
		(pin "H29"
		)
		(pin "J21"
		)
		(pin "J22"
		)
		(pin "J23"
		)
		(pin "J24"
		)
		(pin "J26"
		)
		(pin "J27"
		)
		(pin "J28"
		)
		(pin "J29"
		)
		(pin "K21"
		)
		(pin "K23"
		)
		(pin "K24"
		)
		(pin "K25"
		)
		(pin "K26"
		)
		(pin "K28"
		)
		(pin "K29"
		)
		(pin "K30"
		)
		(pin "L20"
		)
		(pin "L21"
		)
		(pin "L22"
		)
		(pin "L23"
		)
		(pin "L25"
		)
		(pin "L26"
		)
		(pin "L27"
		)
		(pin "L28"
		)
		(pin "L30"
		)
		(pin "M19"
		)
		(pin "M20"
		)
		(pin "M22"
		)
		(pin "M23"
		)
		(pin "M24"
		)
		(pin "M25"
		)
		(pin "M27"
		)
		(pin "M28"
		)
		(pin "M29"
		)
		(pin "M30"
		)
		(pin "N19"
		)
		(pin "N20"
		)
		(pin "N21"
		)
		(pin "N22"
		)
		(pin "N24"
		)
		(pin "N25"
		)
		(pin "N26"
		)
		(pin "N27"
		)
		(pin "N29"
		)
		(pin "N30"
		)
		(pin "P19"
		)
		(pin "P21"
		)
		(pin "P22"
		)
		(pin "P23"
		)
		(pin "A16"
		)
		(pin "A17"
		)
		(pin "A18"
		)
		(pin "A20"
		)
		(pin "A21"
		)
		(pin "A22"
		)
		(pin "B17"
		)
		(pin "B18"
		)
		(pin "B19"
		)
		(pin "B20"
		)
		(pin "B22"
		)
		(pin "C16"
		)
		(pin "C17"
		)
		(pin "C19"
		)
		(pin "C20"
		)
		(pin "C21"
		)
		(pin "C22"
		)
		(pin "D16"
		)
		(pin "D17"
		)
		(pin "D18"
		)
		(pin "D19"
		)
		(pin "D21"
		)
		(pin "D22"
		)
		(pin "E18"
		)
		(pin "E19"
		)
		(pin "E20"
		)
		(pin "E21"
		)
		(pin "F17"
		)
		(pin "F18"
		)
		(pin "F20"
		)
		(pin "F21"
		)
		(pin "F22"
		)
		(pin "G17"
		)
		(pin "G18"
		)
		(pin "G19"
		)
		(pin "G20"
		)
		(pin "G22"
		)
		(pin "H17"
		)
		(pin "H19"
		)
		(pin "H20"
		)
		(pin "H21"
		)
		(pin "H22"
		)
		(pin "J17"
		)
		(pin "J18"
		)
		(pin "J19"
		)
		(pin "K18"
		)
		(pin "K19"
		)
		(pin "K20"
		)
		(pin "L17"
		)
		(pin "L18"
		)
		(pin "AA15"
		)
		(pin "AA16"
		)
		(pin "AA17"
		)
		(pin "AA18"
		)
		(pin "AB14"
		)
		(pin "AB15"
		)
		(pin "AB17"
		)
		(pin "AB18"
		)
		(pin "AB19"
		)
		(pin "AC14"
		)
		(pin "AC15"
		)
		(pin "AC16"
		)
		(pin "AC17"
		)
		(pin "AC19"
		)
		(pin "AD14"
		)
		(pin "AD16"
		)
		(pin "AD17"
		)
		(pin "AD18"
		)
		(pin "AD19"
		)
		(pin "AE14"
		)
		(pin "AE15"
		)
		(pin "AE16"
		)
		(pin "AE18"
		)
		(pin "AE19"
		)
		(pin "AF15"
		)
		(pin "AF16"
		)
		(pin "AF17"
		)
		(pin "AF18"
		)
		(pin "AG14"
		)
		(pin "AG15"
		)
		(pin "AG17"
		)
		(pin "AG18"
		)
		(pin "AG19"
		)
		(pin "AH15"
		)
		(pin "AH16"
		)
		(pin "AH17"
		)
		(pin "AH19"
		)
		(pin "AJ16"
		)
		(pin "AJ17"
		)
		(pin "AJ18"
		)
		(pin "AJ19"
		)
		(pin "AK15"
		)
		(pin "AK16"
		)
		(pin "AK18"
		)
		(pin "AK19"
		)
		(pin "Y14"
		)
		(pin "Y15"
		)
		(pin "Y16"
		)
		(pin "Y18"
		)
		(pin "Y19"
		)
		(pin "AB7"
		)
		(pin "AC1"
		)
		(pin "AC2"
		)
		(pin "AC4"
		)
		(pin "AC5"
		)
		(pin "AC6"
		)
		(pin "AC7"
		)
		(pin "AD1"
		)
		(pin "AD2"
		)
		(pin "AD3"
		)
		(pin "AD4"
		)
		(pin "AD6"
		)
		(pin "AD7"
		)
		(pin "AE1"
		)
		(pin "AE3"
		)
		(pin "AE4"
		)
		(pin "AE5"
		)
		(pin "AE6"
		)
		(pin "AF1"
		)
		(pin "AF2"
		)
		(pin "AF3"
		)
		(pin "AF5"
		)
		(pin "AF6"
		)
		(pin "AF7"
		)
		(pin "AF8"
		)
		(pin "AG2"
		)
		(pin "AG3"
		)
		(pin "AG4"
		)
		(pin "AG5"
		)
		(pin "AG7"
		)
		(pin "AG8"
		)
		(pin "AH1"
		)
		(pin "AH2"
		)
		(pin "AH4"
		)
		(pin "AH5"
		)
		(pin "AH6"
		)
		(pin "AH7"
		)
		(pin "AJ1"
		)
		(pin "AJ2"
		)
		(pin "AJ3"
		)
		(pin "AJ4"
		)
		(pin "AJ6"
		)
		(pin "AJ7"
		)
		(pin "AJ8"
		)
		(pin "AK1"
		)
		(pin "AK3"
		)
		(pin "AK4"
		)
		(pin "AK5"
		)
		(pin "AK6"
		)
		(pin "AK8"
		)
		(instances
			(project "k410t-devboard"
				(path ""
					(reference "U1")
					(unit 2)
				)
			)
		)
	)
	(symbol
		(lib_id "antmicroCapacitors0402:C_100n_0402")
		(at 265.43 64.77 270)
		(mirror x)
		(unit 1)
		(exclude_from_sim no)
		(in_bom yes)
		(on_board yes)
		(dnp no)
		(property "Reference" "C38"
			(at 264.795 60.325 90)
			(effects
				(font
					(size 1.27 1.27)
				)
				(justify right)
			)
		)
		(property "Value" "C_100n_0402"
			(at 255.27 44.45 0)
			(effects
				(font
					(size 1.27 1.27)
					(thickness 0.15)
				)
				(justify left bottom)
				(hide yes)
			)
		)
		(property "Footprint" "antmicro-footprints:C_0402_1005Metric"
			(at 252.73 44.45 0)
			(effects
				(font
					(size 1.27 1.27)
					(thickness 0.15)
				)
				(justify left bottom)
				(hide yes)
			)
		)
		(property "Datasheet" "https://www.murata.com/products/productdetail?partno=GRM155R61H104KE14%23"
			(at 250.19 44.45 0)
			(effects
				(font
					(size 1.27 1.27)
					(thickness 0.15)
				)
				(justify left bottom)
				(hide yes)
			)
		)
		(property "Description" ""
			(at 265.43 64.77 0)
			(effects
				(font
					(size 1.27 1.27)
				)
			)
		)
		(property "Manufacturer" "Murata"
			(at 245.11 44.45 0)
			(effects
				(font
					(size 1.27 1.27)
					(thickness 0.15)
				)
				(justify left bottom)
				(hide yes)
			)
		)
		(property "MPN" "GRM155R61H104KE14D"
			(at 247.65 44.45 0)
			(effects
				(font
					(size 1.27 1.27)
					(thickness 0.15)
				)
				(justify left bottom)
				(hide yes)
			)
		)
		(property "Val" "100n"
			(at 264.795 64.135 90)
			(effects
				(font
					(size 1.27 1.27)
					(thickness 0.15)
				)
				(justify right)
			)
		)
		(property "License" "Apache-2.0"
			(at 242.57 44.45 0)
			(effects
				(font
					(size 1.27 1.27)
					(thickness 0.15)
				)
				(justify left bottom)
				(hide yes)
			)
		)
		(property "Author" "Antmicro"
			(at 240.03 44.45 0)
			(effects
				(font
					(size 1.27 1.27)
					(thickness 0.15)
				)
				(justify left bottom)
				(hide yes)
			)
		)
		(property "Voltage" "50V"
			(at 237.49 44.45 0)
			(effects
				(font
					(size 1.27 1.27)
				)
				(justify left bottom)
				(hide yes)
			)
		)
		(property "Dielectric" "X5R"
			(at 234.95 44.45 0)
			(effects
				(font
					(size 1.27 1.27)
				)
				(justify left bottom)
				(hide yes)
			)
		)
		(pin "1"
		)
		(pin "2"
		)
		(instances
			(project "k410t-devboard"
				(path ""
					(reference "C38")
					(unit 1)
				)
			)
		)
	)
	(symbol
		(lib_id "antmicroCapacitors0402:C_100n_0402")
		(at 280.67 64.77 270)
		(mirror x)
		(unit 1)
		(exclude_from_sim no)
		(in_bom yes)
		(on_board yes)
		(dnp no)
		(property "Reference" "C26"
			(at 280.035 60.325 90)
			(effects
				(font
					(size 1.27 1.27)
				)
				(justify right)
			)
		)
		(property "Value" "C_100n_0402"
			(at 270.51 44.45 0)
			(effects
				(font
					(size 1.27 1.27)
					(thickness 0.15)
				)
				(justify left bottom)
				(hide yes)
			)
		)
		(property "Footprint" "antmicro-footprints:C_0402_1005Metric"
			(at 267.97 44.45 0)
			(effects
				(font
					(size 1.27 1.27)
					(thickness 0.15)
				)
				(justify left bottom)
				(hide yes)
			)
		)
		(property "Datasheet" "https://www.murata.com/products/productdetail?partno=GRM155R61H104KE14%23"
			(at 265.43 44.45 0)
			(effects
				(font
					(size 1.27 1.27)
					(thickness 0.15)
				)
				(justify left bottom)
				(hide yes)
			)
		)
		(property "Description" ""
			(at 280.67 64.77 0)
			(effects
				(font
					(size 1.27 1.27)
				)
			)
		)
		(property "Manufacturer" "Murata"
			(at 260.35 44.45 0)
			(effects
				(font
					(size 1.27 1.27)
					(thickness 0.15)
				)
				(justify left bottom)
				(hide yes)
			)
		)
		(property "MPN" "GRM155R61H104KE14D"
			(at 262.89 44.45 0)
			(effects
				(font
					(size 1.27 1.27)
					(thickness 0.15)
				)
				(justify left bottom)
				(hide yes)
			)
		)
		(property "Val" "100n"
			(at 280.035 64.135 90)
			(effects
				(font
					(size 1.27 1.27)
					(thickness 0.15)
				)
				(justify right)
			)
		)
		(property "License" "Apache-2.0"
			(at 257.81 44.45 0)
			(effects
				(font
					(size 1.27 1.27)
					(thickness 0.15)
				)
				(justify left bottom)
				(hide yes)
			)
		)
		(property "Author" "Antmicro"
			(at 255.27 44.45 0)
			(effects
				(font
					(size 1.27 1.27)
					(thickness 0.15)
				)
				(justify left bottom)
				(hide yes)
			)
		)
		(property "Voltage" "50V"
			(at 252.73 44.45 0)
			(effects
				(font
					(size 1.27 1.27)
				)
				(justify left bottom)
				(hide yes)
			)
		)
		(property "Dielectric" "X5R"
			(at 250.19 44.45 0)
			(effects
				(font
					(size 1.27 1.27)
				)
				(justify left bottom)
				(hide yes)
			)
		)
		(pin "1"
		)
		(pin "2"
		)
		(instances
			(project "k410t-devboard"
				(path ""
					(reference "C26")
					(unit 1)
				)
			)
		)
	)
	(symbol
		(lib_id "k410t-devboard:Net-Tie_2")
		(at 149.86 113.03 0)
		(mirror y)
		(unit 1)
		(exclude_from_sim no)
		(in_bom yes)
		(on_board yes)
		(dnp no)
		(property "Reference" "NT10"
			(at 149.86 111.76 0)
			(effects
				(font
					(size 1.27 1.27)
				)
				(hide yes)
			)
		)
		(property "Value" "Net-Tie_2"
			(at 149.86 112.395 0)
			(effects
				(font
					(size 1.27 1.27)
					(thickness 0.15)
				)
				(justify left bottom)
				(hide yes)
			)
		)
		(property "Footprint" "antmicro-footprints:NetTie-2_SMD_Pad0.127mm"
			(at 128.27 118.11 0)
			(effects
				(font
					(size 1.27 1.27)
					(thickness 0.15)
				)
				(justify left bottom)
				(hide yes)
			)
		)
		(property "Datasheet" ""
			(at 128.27 120.65 0)
			(effects
				(font
					(size 1.27 1.27)
					(thickness 0.15)
				)
				(justify left bottom)
				(hide yes)
			)
		)
		(property "Description" ""
			(at 149.86 113.03 0)
			(effects
				(font
					(size 1.27 1.27)
				)
			)
		)
		(property "MPN" ""
			(at 128.27 121.92 0)
			(effects
				(font
					(size 1.27 1.27)
				)
				(justify left)
				(hide yes)
			)
		)
		(property "Manufacturer" ""
			(at 128.27 124.46 0)
			(effects
				(font
					(size 1.27 1.27)
				)
				(justify left)
				(hide yes)
			)
		)
		(property "Author" "Antmicro"
			(at 128.27 128.27 0)
			(effects
				(font
					(size 1.27 1.27)
					(thickness 0.15)
				)
				(justify left bottom)
				(hide yes)
			)
		)
		(property "License" "Apache-2.0"
			(at 128.27 130.81 0)
			(effects
				(font
					(size 1.27 1.27)
					(thickness 0.15)
				)
				(justify left bottom)
				(hide yes)
			)
		)
		(pin "1"
		)
		(pin "2"
		)
		(instances
			(project "k410t-devboard"
				(path ""
					(reference "NT10")
					(unit 1)
				)
			)
		)
	)
	(symbol
		(lib_id "k410t-devboard:Net-Tie_2")
		(at 127 120.65 0)
		(mirror y)
		(unit 1)
		(exclude_from_sim no)
		(in_bom yes)
		(on_board yes)
		(dnp no)
		(property "Reference" "NT20"
			(at 127 119.38 0)
			(effects
				(font
					(size 1.27 1.27)
				)
				(hide yes)
			)
		)
		(property "Value" "Net-Tie_2"
			(at 104.14 123.19 0)
			(effects
				(font
					(size 1.27 1.27)
					(thickness 0.15)
				)
				(justify left bottom)
				(hide yes)
			)
		)
		(property "Footprint" "antmicro-footprints:NetTie-2_SMD_Pad0.127mm"
			(at 105.41 125.73 0)
			(effects
				(font
					(size 1.27 1.27)
					(thickness 0.15)
				)
				(justify left bottom)
				(hide yes)
			)
		)
		(property "Datasheet" ""
			(at 105.41 128.27 0)
			(effects
				(font
					(size 1.27 1.27)
					(thickness 0.15)
				)
				(justify left bottom)
				(hide yes)
			)
		)
		(property "Description" ""
			(at 127 120.65 0)
			(effects
				(font
					(size 1.27 1.27)
				)
			)
		)
		(property "MPN" ""
			(at 105.41 129.54 0)
			(effects
				(font
					(size 1.27 1.27)
				)
				(justify left)
				(hide yes)
			)
		)
		(property "Manufacturer" ""
			(at 105.41 132.08 0)
			(effects
				(font
					(size 1.27 1.27)
				)
				(justify left)
				(hide yes)
			)
		)
		(property "Author" "Antmicro"
			(at 105.41 135.89 0)
			(effects
				(font
					(size 1.27 1.27)
					(thickness 0.15)
				)
				(justify left bottom)
				(hide yes)
			)
		)
		(property "License" "Apache-2.0"
			(at 105.41 138.43 0)
			(effects
				(font
					(size 1.27 1.27)
					(thickness 0.15)
				)
				(justify left bottom)
				(hide yes)
			)
		)
		(pin "1"
		)
		(pin "2"
		)
		(instances
			(project "k410t-devboard"
				(path ""
					(reference "NT20")
					(unit 1)
				)
			)
		)
	)
	(symbol
		(lib_id "antmicroCapacitors0402:C_100n_0402")
		(at 288.29 64.77 270)
		(mirror x)
		(unit 1)
		(exclude_from_sim no)
		(in_bom yes)
		(on_board yes)
		(dnp no)
		(property "Reference" "C20"
			(at 287.655 60.325 90)
			(effects
				(font
					(size 1.27 1.27)
				)
				(justify right)
			)
		)
		(property "Value" "C_100n_0402"
			(at 278.13 44.45 0)
			(effects
				(font
					(size 1.27 1.27)
					(thickness 0.15)
				)
				(justify left bottom)
				(hide yes)
			)
		)
		(property "Footprint" "antmicro-footprints:C_0402_1005Metric"
			(at 275.59 44.45 0)
			(effects
				(font
					(size 1.27 1.27)
					(thickness 0.15)
				)
				(justify left bottom)
				(hide yes)
			)
		)
		(property "Datasheet" "https://www.murata.com/products/productdetail?partno=GRM155R61H104KE14%23"
			(at 273.05 44.45 0)
			(effects
				(font
					(size 1.27 1.27)
					(thickness 0.15)
				)
				(justify left bottom)
				(hide yes)
			)
		)
		(property "Description" ""
			(at 288.29 64.77 0)
			(effects
				(font
					(size 1.27 1.27)
				)
			)
		)
		(property "Manufacturer" "Murata"
			(at 267.97 44.45 0)
			(effects
				(font
					(size 1.27 1.27)
					(thickness 0.15)
				)
				(justify left bottom)
				(hide yes)
			)
		)
		(property "MPN" "GRM155R61H104KE14D"
			(at 270.51 44.45 0)
			(effects
				(font
					(size 1.27 1.27)
					(thickness 0.15)
				)
				(justify left bottom)
				(hide yes)
			)
		)
		(property "Val" "100n"
			(at 287.655 64.135 90)
			(effects
				(font
					(size 1.27 1.27)
					(thickness 0.15)
				)
				(justify right)
			)
		)
		(property "License" "Apache-2.0"
			(at 265.43 44.45 0)
			(effects
				(font
					(size 1.27 1.27)
					(thickness 0.15)
				)
				(justify left bottom)
				(hide yes)
			)
		)
		(property "Author" "Antmicro"
			(at 262.89 44.45 0)
			(effects
				(font
					(size 1.27 1.27)
					(thickness 0.15)
				)
				(justify left bottom)
				(hide yes)
			)
		)
		(property "Voltage" "50V"
			(at 260.35 44.45 0)
			(effects
				(font
					(size 1.27 1.27)
				)
				(justify left bottom)
				(hide yes)
			)
		)
		(property "Dielectric" "X5R"
			(at 257.81 44.45 0)
			(effects
				(font
					(size 1.27 1.27)
				)
				(justify left bottom)
				(hide yes)
			)
		)
		(pin "1"
		)
		(pin "2"
		)
		(instances
			(project "k410t-devboard"
				(path ""
					(reference "C20")
					(unit 1)
				)
			)
		)
	)
	(symbol
		(lib_id "k410t-devboard:Net-Tie_2")
		(at 127 97.79 0)
		(mirror y)
		(unit 1)
		(exclude_from_sim no)
		(in_bom yes)
		(on_board yes)
		(dnp no)
		(property "Reference" "NT14"
			(at 127 96.52 0)
			(effects
				(font
					(size 1.27 1.27)
				)
				(hide yes)
			)
		)
		(property "Value" "Net-Tie_2"
			(at 127 97.79 0)
			(effects
				(font
					(size 1.27 1.27)
					(thickness 0.15)
				)
				(justify left bottom)
				(hide yes)
			)
		)
		(property "Footprint" "antmicro-footprints:NetTie-2_SMD_Pad0.127mm"
			(at 105.41 102.87 0)
			(effects
				(font
					(size 1.27 1.27)
					(thickness 0.15)
				)
				(justify left bottom)
				(hide yes)
			)
		)
		(property "Datasheet" ""
			(at 105.41 105.41 0)
			(effects
				(font
					(size 1.27 1.27)
					(thickness 0.15)
				)
				(justify left bottom)
				(hide yes)
			)
		)
		(property "Description" ""
			(at 127 97.79 0)
			(effects
				(font
					(size 1.27 1.27)
				)
			)
		)
		(property "MPN" ""
			(at 105.41 106.68 0)
			(effects
				(font
					(size 1.27 1.27)
				)
				(justify left)
				(hide yes)
			)
		)
		(property "Manufacturer" ""
			(at 105.41 109.22 0)
			(effects
				(font
					(size 1.27 1.27)
				)
				(justify left)
				(hide yes)
			)
		)
		(property "Author" "Antmicro"
			(at 105.41 113.03 0)
			(effects
				(font
					(size 1.27 1.27)
					(thickness 0.15)
				)
				(justify left bottom)
				(hide yes)
			)
		)
		(property "License" "Apache-2.0"
			(at 105.41 115.57 0)
			(effects
				(font
					(size 1.27 1.27)
					(thickness 0.15)
				)
				(justify left bottom)
				(hide yes)
			)
		)
		(pin "1"
		)
		(pin "2"
		)
		(instances
			(project "k410t-devboard"
				(path ""
					(reference "NT14")
					(unit 1)
				)
			)
		)
	)
	(symbol
		(lib_id "antmicroCapacitors0402:C_100n_0402")
		(at 130.81 64.77 90)
		(unit 1)
		(exclude_from_sim no)
		(in_bom yes)
		(on_board yes)
		(dnp no)
		(property "Reference" "C13"
			(at 132.08 59.69 90)
			(effects
				(font
					(size 1.27 1.27)
				)
				(justify right)
			)
		)
		(property "Value" "C_100n_0402"
			(at 140.97 44.45 0)
			(effects
				(font
					(size 1.27 1.27)
					(thickness 0.15)
				)
				(justify left bottom)
				(hide yes)
			)
		)
		(property "Footprint" "antmicro-footprints:C_0402_1005Metric"
			(at 143.51 44.45 0)
			(effects
				(font
					(size 1.27 1.27)
					(thickness 0.15)
				)
				(justify left bottom)
				(hide yes)
			)
		)
		(property "Datasheet" "https://www.murata.com/products/productdetail?partno=GRM155R61H104KE14%23"
			(at 146.05 44.45 0)
			(effects
				(font
					(size 1.27 1.27)
					(thickness 0.15)
				)
				(justify left bottom)
				(hide yes)
			)
		)
		(property "Description" ""
			(at 130.81 64.77 0)
			(effects
				(font
					(size 1.27 1.27)
				)
			)
		)
		(property "Manufacturer" "Murata"
			(at 151.13 44.45 0)
			(effects
				(font
					(size 1.27 1.27)
					(thickness 0.15)
				)
				(justify left bottom)
				(hide yes)
			)
		)
		(property "MPN" "GRM155R61H104KE14D"
			(at 148.59 44.45 0)
			(effects
				(font
					(size 1.27 1.27)
					(thickness 0.15)
				)
				(justify left bottom)
				(hide yes)
			)
		)
		(property "Val" "100n"
			(at 132.08 64.77 90)
			(effects
				(font
					(size 1.27 1.27)
					(thickness 0.15)
				)
				(justify right)
			)
		)
		(property "License" "Apache-2.0"
			(at 153.67 44.45 0)
			(effects
				(font
					(size 1.27 1.27)
					(thickness 0.15)
				)
				(justify left bottom)
				(hide yes)
			)
		)
		(property "Author" "Antmicro"
			(at 156.21 44.45 0)
			(effects
				(font
					(size 1.27 1.27)
					(thickness 0.15)
				)
				(justify left bottom)
				(hide yes)
			)
		)
		(property "Voltage" "50V"
			(at 158.75 44.45 0)
			(effects
				(font
					(size 1.27 1.27)
				)
				(justify left bottom)
				(hide yes)
			)
		)
		(property "Dielectric" "X5R"
			(at 161.29 44.45 0)
			(effects
				(font
					(size 1.27 1.27)
				)
				(justify left bottom)
				(hide yes)
			)
		)
		(pin "1"
		)
		(pin "2"
		)
		(instances
			(project "k410t-devboard"
				(path ""
					(reference "C13")
					(unit 1)
				)
			)
		)
	)
	(symbol
		(lib_id "antmicroCapacitors0402:C_100n_0402")
		(at 273.05 64.77 270)
		(mirror x)
		(unit 1)
		(exclude_from_sim no)
		(in_bom yes)
		(on_board yes)
		(dnp no)
		(property "Reference" "C32"
			(at 272.415 60.325 90)
			(effects
				(font
					(size 1.27 1.27)
				)
				(justify right)
			)
		)
		(property "Value" "C_100n_0402"
			(at 262.89 44.45 0)
			(effects
				(font
					(size 1.27 1.27)
					(thickness 0.15)
				)
				(justify left bottom)
				(hide yes)
			)
		)
		(property "Footprint" "antmicro-footprints:C_0402_1005Metric"
			(at 260.35 44.45 0)
			(effects
				(font
					(size 1.27 1.27)
					(thickness 0.15)
				)
				(justify left bottom)
				(hide yes)
			)
		)
		(property "Datasheet" "https://www.murata.com/products/productdetail?partno=GRM155R61H104KE14%23"
			(at 257.81 44.45 0)
			(effects
				(font
					(size 1.27 1.27)
					(thickness 0.15)
				)
				(justify left bottom)
				(hide yes)
			)
		)
		(property "Description" ""
			(at 273.05 64.77 0)
			(effects
				(font
					(size 1.27 1.27)
				)
			)
		)
		(property "Manufacturer" "Murata"
			(at 252.73 44.45 0)
			(effects
				(font
					(size 1.27 1.27)
					(thickness 0.15)
				)
				(justify left bottom)
				(hide yes)
			)
		)
		(property "MPN" "GRM155R61H104KE14D"
			(at 255.27 44.45 0)
			(effects
				(font
					(size 1.27 1.27)
					(thickness 0.15)
				)
				(justify left bottom)
				(hide yes)
			)
		)
		(property "Val" "100n"
			(at 272.415 64.135 90)
			(effects
				(font
					(size 1.27 1.27)
					(thickness 0.15)
				)
				(justify right)
			)
		)
		(property "License" "Apache-2.0"
			(at 250.19 44.45 0)
			(effects
				(font
					(size 1.27 1.27)
					(thickness 0.15)
				)
				(justify left bottom)
				(hide yes)
			)
		)
		(property "Author" "Antmicro"
			(at 247.65 44.45 0)
			(effects
				(font
					(size 1.27 1.27)
					(thickness 0.15)
				)
				(justify left bottom)
				(hide yes)
			)
		)
		(property "Voltage" "50V"
			(at 245.11 44.45 0)
			(effects
				(font
					(size 1.27 1.27)
				)
				(justify left bottom)
				(hide yes)
			)
		)
		(property "Dielectric" "X5R"
			(at 242.57 44.45 0)
			(effects
				(font
					(size 1.27 1.27)
				)
				(justify left bottom)
				(hide yes)
			)
		)
		(pin "1"
		)
		(pin "2"
		)
		(instances
			(project "k410t-devboard"
				(path ""
					(reference "C32")
					(unit 1)
				)
			)
		)
	)
	(symbol
		(lib_id "antmicroCapacitors0603:C_47u_0603")
		(at 303.53 64.77 270)
		(mirror x)
		(unit 1)
		(exclude_from_sim no)
		(in_bom yes)
		(on_board yes)
		(dnp no)
		(property "Reference" "C6"
			(at 302.895 60.325 90)
			(effects
				(font
					(size 1.27 1.27)
				)
				(justify right)
			)
		)
		(property "Value" "C_47u_0603"
			(at 293.37 44.45 0)
			(effects
				(font
					(size 1.27 1.27)
					(thickness 0.15)
				)
				(justify left bottom)
				(hide yes)
			)
		)
		(property "Footprint" "antmicro-footprints:C_0603_1608Metric"
			(at 290.83 44.45 0)
			(effects
				(font
					(size 1.27 1.27)
					(thickness 0.15)
				)
				(justify left bottom)
				(hide yes)
			)
		)
		(property "Datasheet" "https://www.murata.com/products/productdetail?partno=GRM188R60J476ME15%23"
			(at 288.29 44.45 0)
			(effects
				(font
					(size 1.27 1.27)
					(thickness 0.15)
				)
				(justify left bottom)
				(hide yes)
			)
		)
		(property "Description" ""
			(at 303.53 64.77 0)
			(effects
				(font
					(size 1.27 1.27)
				)
			)
		)
		(property "Manufacturer" "Murata"
			(at 283.21 44.45 0)
			(effects
				(font
					(size 1.27 1.27)
					(thickness 0.15)
				)
				(justify left bottom)
				(hide yes)
			)
		)
		(property "MPN" "GRM188R60J476ME15D"
			(at 285.75 44.45 0)
			(effects
				(font
					(size 1.27 1.27)
					(thickness 0.15)
				)
				(justify left bottom)
				(hide yes)
			)
		)
		(property "Val" "47u"
			(at 302.895 64.135 90)
			(effects
				(font
					(size 1.27 1.27)
					(thickness 0.15)
				)
				(justify right)
			)
		)
		(property "License" "Apache-2.0"
			(at 280.67 44.45 0)
			(effects
				(font
					(size 1.27 1.27)
					(thickness 0.15)
				)
				(justify left bottom)
				(hide yes)
			)
		)
		(property "Author" "Antmicro"
			(at 278.13 44.45 0)
			(effects
				(font
					(size 1.27 1.27)
					(thickness 0.15)
				)
				(justify left bottom)
				(hide yes)
			)
		)
		(property "Voltage" ""
			(at 275.59 44.45 0)
			(effects
				(font
					(size 1.27 1.27)
				)
				(justify left bottom)
				(hide yes)
			)
		)
		(property "Dielectric" ""
			(at 273.05 44.45 0)
			(effects
				(font
					(size 1.27 1.27)
				)
				(justify left bottom)
				(hide yes)
			)
		)
		(pin "1"
		)
		(pin "2"
		)
		(instances
			(project "k410t-devboard"
				(path ""
					(reference "C6")
					(unit 1)
				)
			)
		)
	)
	(symbol
		(lib_id "antmicroCapacitors0402:C_100n_0402")
		(at 295.91 64.77 270)
		(mirror x)
		(unit 1)
		(exclude_from_sim no)
		(in_bom yes)
		(on_board yes)
		(dnp no)
		(property "Reference" "C14"
			(at 295.275 60.325 90)
			(effects
				(font
					(size 1.27 1.27)
				)
				(justify right)
			)
		)
		(property "Value" "C_100n_0402"
			(at 285.75 44.45 0)
			(effects
				(font
					(size 1.27 1.27)
					(thickness 0.15)
				)
				(justify left bottom)
				(hide yes)
			)
		)
		(property "Footprint" "antmicro-footprints:C_0402_1005Metric"
			(at 283.21 44.45 0)
			(effects
				(font
					(size 1.27 1.27)
					(thickness 0.15)
				)
				(justify left bottom)
				(hide yes)
			)
		)
		(property "Datasheet" "https://www.murata.com/products/productdetail?partno=GRM155R61H104KE14%23"
			(at 280.67 44.45 0)
			(effects
				(font
					(size 1.27 1.27)
					(thickness 0.15)
				)
				(justify left bottom)
				(hide yes)
			)
		)
		(property "Description" ""
			(at 295.91 64.77 0)
			(effects
				(font
					(size 1.27 1.27)
				)
			)
		)
		(property "Manufacturer" "Murata"
			(at 275.59 44.45 0)
			(effects
				(font
					(size 1.27 1.27)
					(thickness 0.15)
				)
				(justify left bottom)
				(hide yes)
			)
		)
		(property "MPN" "GRM155R61H104KE14D"
			(at 278.13 44.45 0)
			(effects
				(font
					(size 1.27 1.27)
					(thickness 0.15)
				)
				(justify left bottom)
				(hide yes)
			)
		)
		(property "Val" "100n"
			(at 295.275 64.135 90)
			(effects
				(font
					(size 1.27 1.27)
					(thickness 0.15)
				)
				(justify right)
			)
		)
		(property "License" "Apache-2.0"
			(at 273.05 44.45 0)
			(effects
				(font
					(size 1.27 1.27)
					(thickness 0.15)
				)
				(justify left bottom)
				(hide yes)
			)
		)
		(property "Author" "Antmicro"
			(at 270.51 44.45 0)
			(effects
				(font
					(size 1.27 1.27)
					(thickness 0.15)
				)
				(justify left bottom)
				(hide yes)
			)
		)
		(property "Voltage" "50V"
			(at 267.97 44.45 0)
			(effects
				(font
					(size 1.27 1.27)
				)
				(justify left bottom)
				(hide yes)
			)
		)
		(property "Dielectric" "X5R"
			(at 265.43 44.45 0)
			(effects
				(font
					(size 1.27 1.27)
				)
				(justify left bottom)
				(hide yes)
			)
		)
		(pin "1"
		)
		(pin "2"
		)
		(instances
			(project "k410t-devboard"
				(path ""
					(reference "C14")
					(unit 1)
				)
			)
		)
	)
	(symbol
		(lib_id "antmicropower:GND")
		(at 110.49 212.09 0)
		(unit 1)
		(exclude_from_sim no)
		(in_bom yes)
		(on_board yes)
		(dnp no)
		(property "Reference" "#PWR0477"
			(at 110.49 218.44 0)
			(effects
				(font
					(size 1.27 1.27)
				)
				(hide yes)
			)
		)
		(property "Value" "GND"
			(at 110.49 215.9 0)
			(effects
				(font
					(size 1.27 1.27)
				)
			)
		)
		(property "Footprint" ""
			(at 119.38 219.71 0)
			(effects
				(font
					(size 1.27 1.27)
					(thickness 0.15)
				)
				(justify left bottom)
				(hide yes)
			)
		)
		(property "Datasheet" ""
			(at 119.38 224.79 0)
			(effects
				(font
					(size 1.27 1.27)
					(thickness 0.15)
				)
				(justify left bottom)
				(hide yes)
			)
		)
		(property "Description" ""
			(at 110.49 212.09 0)
			(effects
				(font
					(size 1.27 1.27)
				)
			)
		)
		(property "Author" "Antmicro"
			(at 119.38 219.71 0)
			(effects
				(font
					(size 1.27 1.27)
					(thickness 0.15)
				)
				(justify left bottom)
				(hide yes)
			)
		)
		(property "License" "Apache-2.0"
			(at 119.38 222.25 0)
			(effects
				(font
					(size 1.27 1.27)
					(thickness 0.15)
				)
				(justify left bottom)
				(hide yes)
			)
		)
		(pin "1"
		)
		(instances
			(project "k410t-devboard"
				(path ""
					(reference "#PWR0477")
					(unit 1)
				)
			)
		)
	)
	(symbol
		(lib_id "antmicroCapacitors0402:C_100n_0402")
		(at 257.81 64.77 270)
		(mirror x)
		(unit 1)
		(exclude_from_sim no)
		(in_bom yes)
		(on_board yes)
		(dnp no)
		(property "Reference" "C43"
			(at 257.175 60.325 90)
			(effects
				(font
					(size 1.27 1.27)
				)
				(justify right)
			)
		)
		(property "Value" "C_100n_0402"
			(at 247.65 44.45 0)
			(effects
				(font
					(size 1.27 1.27)
					(thickness 0.15)
				)
				(justify left bottom)
				(hide yes)
			)
		)
		(property "Footprint" "antmicro-footprints:C_0402_1005Metric"
			(at 245.11 44.45 0)
			(effects
				(font
					(size 1.27 1.27)
					(thickness 0.15)
				)
				(justify left bottom)
				(hide yes)
			)
		)
		(property "Datasheet" "https://www.murata.com/products/productdetail?partno=GRM155R61H104KE14%23"
			(at 242.57 44.45 0)
			(effects
				(font
					(size 1.27 1.27)
					(thickness 0.15)
				)
				(justify left bottom)
				(hide yes)
			)
		)
		(property "Description" ""
			(at 257.81 64.77 0)
			(effects
				(font
					(size 1.27 1.27)
				)
			)
		)
		(property "Manufacturer" "Murata"
			(at 237.49 44.45 0)
			(effects
				(font
					(size 1.27 1.27)
					(thickness 0.15)
				)
				(justify left bottom)
				(hide yes)
			)
		)
		(property "MPN" "GRM155R61H104KE14D"
			(at 240.03 44.45 0)
			(effects
				(font
					(size 1.27 1.27)
					(thickness 0.15)
				)
				(justify left bottom)
				(hide yes)
			)
		)
		(property "Val" "100n"
			(at 257.175 64.135 90)
			(effects
				(font
					(size 1.27 1.27)
					(thickness 0.15)
				)
				(justify right)
			)
		)
		(property "License" "Apache-2.0"
			(at 234.95 44.45 0)
			(effects
				(font
					(size 1.27 1.27)
					(thickness 0.15)
				)
				(justify left bottom)
				(hide yes)
			)
		)
		(property "Author" "Antmicro"
			(at 232.41 44.45 0)
			(effects
				(font
					(size 1.27 1.27)
					(thickness 0.15)
				)
				(justify left bottom)
				(hide yes)
			)
		)
		(property "Voltage" "50V"
			(at 229.87 44.45 0)
			(effects
				(font
					(size 1.27 1.27)
				)
				(justify left bottom)
				(hide yes)
			)
		)
		(property "Dielectric" "X5R"
			(at 227.33 44.45 0)
			(effects
				(font
					(size 1.27 1.27)
				)
				(justify left bottom)
				(hide yes)
			)
		)
		(pin "1"
		)
		(pin "2"
		)
		(instances
			(project "k410t-devboard"
				(path ""
					(reference "C43")
					(unit 1)
				)
			)
		)
	)
	(symbol
		(lib_id "k410t-devboard:Net-Tie_2")
		(at 149.86 118.11 0)
		(mirror y)
		(unit 1)
		(exclude_from_sim no)
		(in_bom yes)
		(on_board yes)
		(dnp no)
		(property "Reference" "NT12"
			(at 149.86 116.84 0)
			(effects
				(font
					(size 1.27 1.27)
				)
				(hide yes)
			)
		)
		(property "Value" "Net-Tie_2"
			(at 147.32 117.475 0)
			(effects
				(font
					(size 1.27 1.27)
					(thickness 0.15)
				)
				(justify left bottom)
				(hide yes)
			)
		)
		(property "Footprint" "antmicro-footprints:NetTie-2_SMD_Pad0.127mm"
			(at 128.27 123.19 0)
			(effects
				(font
					(size 1.27 1.27)
					(thickness 0.15)
				)
				(justify left bottom)
				(hide yes)
			)
		)
		(property "Datasheet" ""
			(at 128.27 125.73 0)
			(effects
				(font
					(size 1.27 1.27)
					(thickness 0.15)
				)
				(justify left bottom)
				(hide yes)
			)
		)
		(property "Description" ""
			(at 149.86 118.11 0)
			(effects
				(font
					(size 1.27 1.27)
				)
			)
		)
		(property "MPN" ""
			(at 128.27 127 0)
			(effects
				(font
					(size 1.27 1.27)
				)
				(justify left)
				(hide yes)
			)
		)
		(property "Manufacturer" ""
			(at 128.27 129.54 0)
			(effects
				(font
					(size 1.27 1.27)
				)
				(justify left)
				(hide yes)
			)
		)
		(property "Author" "Antmicro"
			(at 128.27 133.35 0)
			(effects
				(font
					(size 1.27 1.27)
					(thickness 0.15)
				)
				(justify left bottom)
				(hide yes)
			)
		)
		(property "License" "Apache-2.0"
			(at 128.27 135.89 0)
			(effects
				(font
					(size 1.27 1.27)
					(thickness 0.15)
				)
				(justify left bottom)
				(hide yes)
			)
		)
		(pin "1"
		)
		(pin "2"
		)
		(instances
			(project "k410t-devboard"
				(path ""
					(reference "NT12")
					(unit 1)
				)
			)
		)
	)
	(symbol
		(lib_id "antmicroCapacitors0603:C_47u_0603")
		(at 123.19 64.77 90)
		(unit 1)
		(exclude_from_sim no)
		(in_bom yes)
		(on_board yes)
		(dnp no)
		(property "Reference" "C5"
			(at 125.73 59.69 90)
			(effects
				(font
					(size 1.27 1.27)
				)
				(justify left)
			)
		)
		(property "Value" "C_47u_0603"
			(at 133.35 44.45 0)
			(effects
				(font
					(size 1.27 1.27)
					(thickness 0.15)
				)
				(justify left bottom)
				(hide yes)
			)
		)
		(property "Footprint" "antmicro-footprints:C_0603_1608Metric"
			(at 135.89 44.45 0)
			(effects
				(font
					(size 1.27 1.27)
					(thickness 0.15)
				)
				(justify left bottom)
				(hide yes)
			)
		)
		(property "Datasheet" "https://www.murata.com/products/productdetail?partno=GRM188R60J476ME15%23"
			(at 138.43 44.45 0)
			(effects
				(font
					(size 1.27 1.27)
					(thickness 0.15)
				)
				(justify left bottom)
				(hide yes)
			)
		)
		(property "Description" ""
			(at 123.19 64.77 0)
			(effects
				(font
					(size 1.27 1.27)
				)
			)
		)
		(property "Manufacturer" "Murata"
			(at 143.51 44.45 0)
			(effects
				(font
					(size 1.27 1.27)
					(thickness 0.15)
				)
				(justify left bottom)
				(hide yes)
			)
		)
		(property "MPN" "GRM188R60J476ME15D"
			(at 140.97 44.45 0)
			(effects
				(font
					(size 1.27 1.27)
					(thickness 0.15)
				)
				(justify left bottom)
				(hide yes)
			)
		)
		(property "Val" "47u"
			(at 127 64.77 90)
			(effects
				(font
					(size 1.27 1.27)
					(thickness 0.15)
				)
				(justify left)
			)
		)
		(property "License" "Apache-2.0"
			(at 146.05 44.45 0)
			(effects
				(font
					(size 1.27 1.27)
					(thickness 0.15)
				)
				(justify left bottom)
				(hide yes)
			)
		)
		(property "Author" "Antmicro"
			(at 148.59 44.45 0)
			(effects
				(font
					(size 1.27 1.27)
					(thickness 0.15)
				)
				(justify left bottom)
				(hide yes)
			)
		)
		(property "Voltage" ""
			(at 151.13 44.45 0)
			(effects
				(font
					(size 1.27 1.27)
				)
				(justify left bottom)
				(hide yes)
			)
		)
		(property "Dielectric" ""
			(at 153.67 44.45 0)
			(effects
				(font
					(size 1.27 1.27)
				)
				(justify left bottom)
				(hide yes)
			)
		)
		(pin "1"
		)
		(pin "2"
		)
		(instances
			(project "k410t-devboard"
				(path ""
					(reference "C5")
					(unit 1)
				)
			)
		)
	)
	(symbol
		(lib_id "antmicroCapacitors0402:C_100n_0402")
		(at 146.05 64.77 90)
		(unit 1)
		(exclude_from_sim no)
		(in_bom yes)
		(on_board yes)
		(dnp no)
		(property "Reference" "C25"
			(at 147.32 59.69 90)
			(effects
				(font
					(size 1.27 1.27)
				)
				(justify right)
			)
		)
		(property "Value" "C_100n_0402"
			(at 156.21 44.45 0)
			(effects
				(font
					(size 1.27 1.27)
					(thickness 0.15)
				)
				(justify left bottom)
				(hide yes)
			)
		)
		(property "Footprint" "antmicro-footprints:C_0402_1005Metric"
			(at 158.75 44.45 0)
			(effects
				(font
					(size 1.27 1.27)
					(thickness 0.15)
				)
				(justify left bottom)
				(hide yes)
			)
		)
		(property "Datasheet" "https://www.murata.com/products/productdetail?partno=GRM155R61H104KE14%23"
			(at 161.29 44.45 0)
			(effects
				(font
					(size 1.27 1.27)
					(thickness 0.15)
				)
				(justify left bottom)
				(hide yes)
			)
		)
		(property "Description" ""
			(at 146.05 64.77 0)
			(effects
				(font
					(size 1.27 1.27)
				)
			)
		)
		(property "Manufacturer" "Murata"
			(at 166.37 44.45 0)
			(effects
				(font
					(size 1.27 1.27)
					(thickness 0.15)
				)
				(justify left bottom)
				(hide yes)
			)
		)
		(property "MPN" "GRM155R61H104KE14D"
			(at 163.83 44.45 0)
			(effects
				(font
					(size 1.27 1.27)
					(thickness 0.15)
				)
				(justify left bottom)
				(hide yes)
			)
		)
		(property "Val" "100n"
			(at 147.32 64.77 90)
			(effects
				(font
					(size 1.27 1.27)
					(thickness 0.15)
				)
				(justify right)
			)
		)
		(property "License" "Apache-2.0"
			(at 168.91 44.45 0)
			(effects
				(font
					(size 1.27 1.27)
					(thickness 0.15)
				)
				(justify left bottom)
				(hide yes)
			)
		)
		(property "Author" "Antmicro"
			(at 171.45 44.45 0)
			(effects
				(font
					(size 1.27 1.27)
					(thickness 0.15)
				)
				(justify left bottom)
				(hide yes)
			)
		)
		(property "Voltage" "50V"
			(at 173.99 44.45 0)
			(effects
				(font
					(size 1.27 1.27)
				)
				(justify left bottom)
				(hide yes)
			)
		)
		(property "Dielectric" "X5R"
			(at 176.53 44.45 0)
			(effects
				(font
					(size 1.27 1.27)
				)
				(justify left bottom)
				(hide yes)
			)
		)
		(pin "1"
		)
		(pin "2"
		)
		(instances
			(project "k410t-devboard"
				(path ""
					(reference "C25")
					(unit 1)
				)
			)
		)
	)
	(symbol
		(lib_id "antmicropower:GND")
		(at 123.19 68.58 0)
		(unit 1)
		(exclude_from_sim no)
		(in_bom yes)
		(on_board yes)
		(dnp no)
		(property "Reference" "#PWR014"
			(at 123.19 74.93 0)
			(effects
				(font
					(size 1.27 1.27)
				)
				(hide yes)
			)
		)
		(property "Value" "GND"
			(at 123.19 72.39 0)
			(effects
				(font
					(size 1.27 1.27)
				)
			)
		)
		(property "Footprint" ""
			(at 132.08 76.2 0)
			(effects
				(font
					(size 1.27 1.27)
					(thickness 0.15)
				)
				(justify left bottom)
				(hide yes)
			)
		)
		(property "Datasheet" ""
			(at 132.08 81.28 0)
			(effects
				(font
					(size 1.27 1.27)
					(thickness 0.15)
				)
				(justify left bottom)
				(hide yes)
			)
		)
		(property "Description" ""
			(at 123.19 68.58 0)
			(effects
				(font
					(size 1.27 1.27)
				)
			)
		)
		(property "Author" "Antmicro"
			(at 132.08 76.2 0)
			(effects
				(font
					(size 1.27 1.27)
					(thickness 0.15)
				)
				(justify left bottom)
				(hide yes)
			)
		)
		(property "License" "Apache-2.0"
			(at 132.08 78.74 0)
			(effects
				(font
					(size 1.27 1.27)
					(thickness 0.15)
				)
				(justify left bottom)
				(hide yes)
			)
		)
		(pin "1"
		)
		(instances
			(project "k410t-devboard"
				(path ""
					(reference "#PWR014")
					(unit 1)
				)
			)
		)
	)
	(symbol
		(lib_id "k410t-devboard:Net-Tie_2")
		(at 127 95.25 0)
		(mirror y)
		(unit 1)
		(exclude_from_sim no)
		(in_bom yes)
		(on_board yes)
		(dnp no)
		(property "Reference" "NT13"
			(at 127 93.98 0)
			(effects
				(font
					(size 1.27 1.27)
				)
				(hide yes)
			)
		)
		(property "Value" "Net-Tie_2"
			(at 127.635 93.98 0)
			(effects
				(font
					(size 1.27 1.27)
					(thickness 0.15)
				)
				(justify left bottom)
				(hide yes)
			)
		)
		(property "Footprint" "antmicro-footprints:NetTie-2_SMD_Pad0.127mm"
			(at 105.41 100.33 0)
			(effects
				(font
					(size 1.27 1.27)
					(thickness 0.15)
				)
				(justify left bottom)
				(hide yes)
			)
		)
		(property "Datasheet" ""
			(at 105.41 102.87 0)
			(effects
				(font
					(size 1.27 1.27)
					(thickness 0.15)
				)
				(justify left bottom)
				(hide yes)
			)
		)
		(property "Description" ""
			(at 127 95.25 0)
			(effects
				(font
					(size 1.27 1.27)
				)
			)
		)
		(property "MPN" ""
			(at 105.41 104.14 0)
			(effects
				(font
					(size 1.27 1.27)
				)
				(justify left)
				(hide yes)
			)
		)
		(property "Manufacturer" ""
			(at 105.41 106.68 0)
			(effects
				(font
					(size 1.27 1.27)
				)
				(justify left)
				(hide yes)
			)
		)
		(property "Author" "Antmicro"
			(at 105.41 110.49 0)
			(effects
				(font
					(size 1.27 1.27)
					(thickness 0.15)
				)
				(justify left bottom)
				(hide yes)
			)
		)
		(property "License" "Apache-2.0"
			(at 105.41 113.03 0)
			(effects
				(font
					(size 1.27 1.27)
					(thickness 0.15)
				)
				(justify left bottom)
				(hide yes)
			)
		)
		(pin "1"
		)
		(pin "2"
		)
		(instances
			(project "k410t-devboard"
				(path ""
					(reference "NT13")
					(unit 1)
				)
			)
		)
	)
	(symbol
		(lib_id "antmicropower:GND")
		(at 303.53 68.58 0)
		(mirror y)
		(unit 1)
		(exclude_from_sim no)
		(in_bom yes)
		(on_board yes)
		(dnp no)
		(property "Reference" "#PWR016"
			(at 303.53 74.93 0)
			(effects
				(font
					(size 1.27 1.27)
				)
				(hide yes)
			)
		)
		(property "Value" "GND"
			(at 303.53 72.39 0)
			(effects
				(font
					(size 1.27 1.27)
				)
			)
		)
		(property "Footprint" ""
			(at 294.64 76.2 0)
			(effects
				(font
					(size 1.27 1.27)
					(thickness 0.15)
				)
				(justify left bottom)
				(hide yes)
			)
		)
		(property "Datasheet" ""
			(at 294.64 81.28 0)
			(effects
				(font
					(size 1.27 1.27)
					(thickness 0.15)
				)
				(justify left bottom)
				(hide yes)
			)
		)
		(property "Description" ""
			(at 303.53 68.58 0)
			(effects
				(font
					(size 1.27 1.27)
				)
			)
		)
		(property "Author" "Antmicro"
			(at 294.64 76.2 0)
			(effects
				(font
					(size 1.27 1.27)
					(thickness 0.15)
				)
				(justify left bottom)
				(hide yes)
			)
		)
		(property "License" "Apache-2.0"
			(at 294.64 78.74 0)
			(effects
				(font
					(size 1.27 1.27)
					(thickness 0.15)
				)
				(justify left bottom)
				(hide yes)
			)
		)
		(pin "1"
		)
		(instances
			(project "k410t-devboard"
				(path ""
					(reference "#PWR016")
					(unit 1)
				)
			)
		)
	)
)
